FILE_TYPE = MACRO_DRAWING;
SET COLOR_WIRE YELLOW;
SET COLOR_PROP MONO;
SET COLOR_DOT WHITE;
SET COLOR_ARC YELLOW;
SET COLOR_BODY GREEN;
SET COLOR_NOTE MONO;
SET PROP_DISPLAY VALUE;
SET PAGE_NUMBER P225;
FORCEADD PVDDQ_GHJ..1
(2550 2000);
FORCEPROP 3 LASTPIN (2550 1950) SIG_NAME PVDDQ_GHJ\g
J 0
(2560 1960);
DISPLAY 0.659574 (2560 1960);
PAINT MONO (2560 1960);
DISPLAY INVISIBLE (2560 1960);
FORCEPROP 2 LAST CDS_LIB mstr_symbols
J 0
(2550 2000);
PAINT ORANGE (2550 2000);
DISPLAY INVISIBLE (2550 2000);
FORCEPROP 1 LAST VOLTAGE 1.2V
J 0
(2505 1957);
DISPLAY 0.340426 (2505 1957);
PAINT SKYBLUE (2505 1957);
DISPLAY INVISIBLE (2505 1957);
FORCEPROP 1 LAST PATH I109
J 0
(2600 2025);
DISPLAY 0.872340 (2600 2025);
PAINT AQUA (2600 2025);
DISPLAY INVISIBLE (2600 2025);
FORCEPROP 2 LAST BOM_COST MEM_VRD_PVDDQ_CD
J 0
(2625 2100);
PAINT MONO (2625 2100);
DISPLAY INVISIBLE (2625 2100);
FORCEPROP 2 LAST ROOM VDDQ_GHJ_PWR_VR
J 0
(2800 2100);
PAINT ORANGE (2800 2100);
DISPLAY INVISIBLE (2800 2100);
FORCEPROP 1 LAST BODY_TYPE PLUMBING
J 0
(2505 1957);
DISPLAY 0.340426 (2505 1957);
PAINT GREEN (2505 1957);
DISPLAY INVISIBLE (2505 1957);
FORCEPROP 1 LAST HDL_POWER PVDDQ_GHJ
J 1
(2550 2050);
DISPLAY 0.872340 (2550 2050);
PAINT GREEN (2550 2050);
DISPLAY INVISIBLE (2550 2050);
FORCEADD GND..1
(4275 1350);
FORCEPROP 3 LASTPIN (4275 1400) SIG_NAME GND\g
J 0
(4285 1410);
DISPLAY 0.659574 (4285 1410);
PAINT MONO (4285 1410);
DISPLAY INVISIBLE (4285 1410);
FORCEPROP 2 LAST ROOM VDDQ_GHJ_PWR_VR
J 0
(3725 1425);
PAINT ORANGE (3725 1425);
DISPLAY INVISIBLE (3725 1425);
FORCEPROP 2 LAST BOM_COST MEM_VRD_PVDDQ_CD
J 0
(3950 1425);
PAINT MONO (3950 1425);
DISPLAY INVISIBLE (3950 1425);
FORCEPROP 1 LAST VOLTAGE 0
J 0
(4275 1350);
PAINT SKYBLUE (4275 1350);
DISPLAY INVISIBLE (4275 1350);
FORCEPROP 2 LAST CDS_LIB mstr_symbols
J 0
(4275 1350);
PAINT ORANGE (4275 1350);
DISPLAY INVISIBLE (4275 1350);
FORCEPROP 1 LAST SIZE 1B
J 0
(4350 1300);
DISPLAY 0.893617 (4350 1300);
PAINT GREEN (4350 1300);
DISPLAY INVISIBLE (4350 1300);
FORCEPROP 1 LAST PATH I114
J 0
(4350 1350);
DISPLAY 1.170213 (4350 1350);
PAINT AQUA (4350 1350);
DISPLAY INVISIBLE (4350 1350);
FORCEPROP 1 LAST BODY_TYPE PLUMBING
J 0
(4230 1307);
DISPLAY 0.340426 (4230 1307);
PAINT GREEN (4230 1307);
DISPLAY INVISIBLE (4230 1307);
FORCEPROP 1 LAST HDL_POWER GND
J 0
(4275 1500);
DISPLAY 0.893617 (4275 1500);
PAINT GREEN (4275 1500);
DISPLAY INVISIBLE (4275 1500);
FORCEADD VCC_CORE..1
(-1250 1575);
FORCEPROP 3 LASTPIN (-1250 1525) SIG_NAME VR_FET_SW_P12V_STBY_PVDDQ_GHJ\g
J 0
(-1240 1535);
DISPLAY 0.659574 (-1240 1535);
PAINT MONO (-1240 1535);
DISPLAY INVISIBLE (-1240 1535);
FORCEPROP 1 LAST HDL_POWER VR_FET_SW_P12V_STBY_PVDDQ_GHJ
J 1
(-1250 1625);
DISPLAY 0.617021 (-1250 1625);
PAINT GREEN (-1250 1625);
FORCEPROP 2 LAST CDS_LIB mstr_symbols
J 0
(-1250 1575);
PAINT ORANGE (-1250 1575);
DISPLAY INVISIBLE (-1250 1575);
FORCEPROP 1 LAST PATH I120
J 0
(-1200 1600);
DISPLAY 1.170213 (-1200 1600);
PAINT AQUA (-1200 1600);
DISPLAY INVISIBLE (-1200 1600);
FORCEADD GND..1
(-1250 875);
FORCEPROP 3 LASTPIN (-1250 925) SIG_NAME GND\g
J 0
(-1240 935);
DISPLAY 0.659574 (-1240 935);
PAINT MONO (-1240 935);
DISPLAY INVISIBLE (-1240 935);
FORCEPROP 1 LAST PATH I123
J 0
(-1175 875);
DISPLAY 1.170213 (-1175 875);
PAINT AQUA (-1175 875);
DISPLAY INVISIBLE (-1175 875);
FORCEPROP 2 LAST CDS_LIB mstr_symbols
J 0
(-1250 875);
PAINT ORANGE (-1250 875);
DISPLAY INVISIBLE (-1250 875);
FORCEPROP 1 LAST SIZE 1B
J 0
(-1175 825);
DISPLAY 0.893617 (-1175 825);
PAINT GREEN (-1175 825);
DISPLAY INVISIBLE (-1175 825);
FORCEPROP 1 LAST VOLTAGE 0
J 0
(-1250 875);
PAINT SKYBLUE (-1250 875);
DISPLAY INVISIBLE (-1250 875);
FORCEPROP 2 LAST ROOM VDDQ_GHJ_PWR_VR
J 0
(-1800 950);
PAINT ORANGE (-1800 950);
DISPLAY INVISIBLE (-1800 950);
FORCEPROP 2 LAST BOM_COST MEM_VRD_PVDDQ_CD
J 0
(-1575 950);
PAINT MONO (-1575 950);
DISPLAY INVISIBLE (-1575 950);
FORCEPROP 1 LAST BODY_TYPE PLUMBING
J 0
(-1295 832);
DISPLAY 0.340426 (-1295 832);
PAINT GREEN (-1295 832);
DISPLAY INVISIBLE (-1295 832);
FORCEPROP 1 LAST HDL_POWER GND
J 0
(-1250 1025);
DISPLAY 0.893617 (-1250 1025);
PAINT GREEN (-1250 1025);
DISPLAY INVISIBLE (-1250 1025);
FORCEADD P12V_STBY..1
(-2025 1550);
FORCEPROP 3 LASTPIN (-2025 1500) SIG_NAME P12V_STBY\g
J 0
(-2015 1510);
DISPLAY 0.659574 (-2015 1510);
PAINT MONO (-2015 1510);
DISPLAY INVISIBLE (-2015 1510);
FORCEPROP 1 LAST VOLTAGE 12.0V
J 0
(-2070 1507);
DISPLAY 0.340426 (-2070 1507);
PAINT SKYBLUE (-2070 1507);
DISPLAY INVISIBLE (-2070 1507);
FORCEPROP 1 LAST SIZE 1B
J 0
(-1980 1572);
DISPLAY 0.340426 (-1980 1572);
PAINT GREEN (-1980 1572);
DISPLAY INVISIBLE (-1980 1572);
FORCEPROP 2 LAST CDS_LIB mstr_symbols
J 0
(-2025 1550);
PAINT ORANGE (-2025 1550);
DISPLAY INVISIBLE (-2025 1550);
FORCEPROP 1 LAST PATH I176
J 0
(-1980 1552);
DISPLAY 0.340426 (-1980 1552);
PAINT GREEN (-1980 1552);
DISPLAY INVISIBLE (-1980 1552);
FORCEPROP 1 LAST BODY_TYPE PLUMBING
J 0
(-2070 1507);
DISPLAY 0.340426 (-2070 1507);
PAINT GREEN (-2070 1507);
DISPLAY INVISIBLE (-2070 1507);
FORCEPROP 1 LAST HDL_POWER P12V_STBY
J 0
(-2325 1425);
DISPLAY 0.872340 (-2325 1425);
PAINT ORANGE (-2325 1425);
DISPLAY INVISIBLE (-2325 1425);
FORCEADD GND..1
(-350 2725);
FORCEPROP 3 LASTPIN (-350 2775) SIG_NAME GND\g
J 0
(-340 2785);
DISPLAY 0.659574 (-340 2785);
PAINT MONO (-340 2785);
DISPLAY INVISIBLE (-340 2785);
FORCEPROP 1 LAST SIZE 1B
J 0
(-275 2675);
DISPLAY 0.893617 (-275 2675);
PAINT GREEN (-275 2675);
DISPLAY INVISIBLE (-275 2675);
FORCEPROP 1 LAST PATH I182
J 0
(-275 2725);
DISPLAY 0.872340 (-275 2725);
PAINT AQUA (-275 2725);
DISPLAY INVISIBLE (-275 2725);
FORCEPROP 2 LAST CDS_LIB mstr_symbols
J 0
(-350 2725);
PAINT ORANGE (-350 2725);
DISPLAY INVISIBLE (-350 2725);
FORCEPROP 1 LAST VOLTAGE 0
J 0
(-350 2725);
PAINT SKYBLUE (-350 2725);
DISPLAY INVISIBLE (-350 2725);
FORCEPROP 2 LAST ROOM VDDQ_ABC_PWR_VR
J 0
(-900 2800);
PAINT ORANGE (-900 2800);
DISPLAY INVISIBLE (-900 2800);
FORCEPROP 2 LAST BOM_COST MEM_VRD_PVDDQ_CD
J 0
(-675 2800);
PAINT MONO (-675 2800);
DISPLAY INVISIBLE (-675 2800);
FORCEPROP 1 LAST BODY_TYPE PLUMBING
J 0
(-395 2682);
DISPLAY 0.340426 (-395 2682);
PAINT GREEN (-395 2682);
DISPLAY INVISIBLE (-395 2682);
FORCEPROP 1 LAST HDL_POWER GND
J 0
(-350 2875);
DISPLAY 0.893617 (-350 2875);
PAINT GREEN (-350 2875);
DISPLAY INVISIBLE (-350 2875);
FORCEADD PVDDQ_GHJ..1
(-2325 3375);
FORCEPROP 3 LASTPIN (-2325 3325) SIG_NAME PVDDQ_GHJ\g
J 0
(-2315 3335);
DISPLAY 0.659574 (-2315 3335);
PAINT MONO (-2315 3335);
DISPLAY INVISIBLE (-2315 3335);
FORCEPROP 2 LAST BOM_COST MEM_VRD_PVPP_AB
J 0
(-2275 3475);
PAINT MONO (-2275 3475);
DISPLAY INVISIBLE (-2275 3475);
FORCEPROP 1 LAST PATH I185
J 0
(-2275 3400);
DISPLAY 0.872340 (-2275 3400);
PAINT AQUA (-2275 3400);
DISPLAY INVISIBLE (-2275 3400);
FORCEPROP 2 LAST ROOM VDDQ_GHJ_PWR_VR
J 0
(-2100 3475);
PAINT ORANGE (-2100 3475);
DISPLAY INVISIBLE (-2100 3475);
FORCEPROP 2 LAST CDS_LIB mstr_symbols
J 0
(-2325 3375);
PAINT ORANGE (-2325 3375);
DISPLAY INVISIBLE (-2325 3375);
FORCEPROP 1 LAST VOLTAGE 1.2V
J 0
(-2370 3332);
DISPLAY 0.340426 (-2370 3332);
PAINT SKYBLUE (-2370 3332);
DISPLAY INVISIBLE (-2370 3332);
FORCEPROP 1 LAST BODY_TYPE PLUMBING
J 0
(-2370 3332);
DISPLAY 0.340426 (-2370 3332);
PAINT GREEN (-2370 3332);
DISPLAY INVISIBLE (-2370 3332);
FORCEPROP 1 LAST HDL_POWER PVDDQ_GHJ
J 1
(-2325 3425);
DISPLAY 0.872340 (-2325 3425);
PAINT GREEN (-2325 3425);
DISPLAY INVISIBLE (-2325 3425);
FORCEADD PVDDQ_GHJ..1
(2600 1250);
FORCEPROP 3 LASTPIN (2600 1200) SIG_NAME PVDDQ_GHJ\g
J 0
(2610 1210);
DISPLAY 0.659574 (2610 1210);
PAINT MONO (2610 1210);
DISPLAY INVISIBLE (2610 1210);
FORCEPROP 1 LAST VOLTAGE 1.2V
J 0
(2555 1207);
DISPLAY 0.340426 (2555 1207);
PAINT SKYBLUE (2555 1207);
DISPLAY INVISIBLE (2555 1207);
FORCEPROP 2 LAST CDS_LIB mstr_symbols
J 0
(2600 1250);
PAINT ORANGE (2600 1250);
DISPLAY INVISIBLE (2600 1250);
FORCEPROP 1 LAST PATH I189
J 0
(2650 1275);
DISPLAY 0.872340 (2650 1275);
PAINT AQUA (2650 1275);
DISPLAY INVISIBLE (2650 1275);
FORCEPROP 2 LAST BOM_COST MEM_VRD_PVDDQ_CD
J 0
(2675 1350);
PAINT MONO (2675 1350);
DISPLAY INVISIBLE (2675 1350);
FORCEPROP 2 LAST ROOM VDDQ_GHJ_PWR_VR
J 0
(2850 1350);
PAINT ORANGE (2850 1350);
DISPLAY INVISIBLE (2850 1350);
FORCEPROP 1 LAST BODY_TYPE PLUMBING
J 0
(2555 1207);
DISPLAY 0.340426 (2555 1207);
PAINT GREEN (2555 1207);
DISPLAY INVISIBLE (2555 1207);
FORCEPROP 1 LAST HDL_POWER PVDDQ_GHJ
J 1
(2600 1300);
DISPLAY 0.872340 (2600 1300);
PAINT GREEN (2600 1300);
DISPLAY INVISIBLE (2600 1300);
FORCEADD GND..1
(3425 575);
FORCEPROP 3 LASTPIN (3425 625) SIG_NAME GND\g
J 0
(3435 635);
DISPLAY 0.659574 (3435 635);
PAINT MONO (3435 635);
DISPLAY INVISIBLE (3435 635);
FORCEPROP 2 LAST ROOM VDDQ_GHJ_PWR_VR
J 0
(2875 650);
PAINT ORANGE (2875 650);
DISPLAY INVISIBLE (2875 650);
FORCEPROP 2 LAST BOM_COST MEM_VRD_PVDDQ_CD
J 0
(3100 650);
PAINT MONO (3100 650);
DISPLAY INVISIBLE (3100 650);
FORCEPROP 1 LAST VOLTAGE 0
J 0
(3425 575);
PAINT SKYBLUE (3425 575);
DISPLAY INVISIBLE (3425 575);
FORCEPROP 2 LAST CDS_LIB mstr_symbols
J 0
(3425 575);
PAINT ORANGE (3425 575);
DISPLAY INVISIBLE (3425 575);
FORCEPROP 1 LAST PATH I191
J 0
(3500 575);
DISPLAY 0.872340 (3500 575);
PAINT AQUA (3500 575);
DISPLAY INVISIBLE (3500 575);
FORCEPROP 1 LAST SIZE 1B
J 0
(3500 525);
DISPLAY 0.893617 (3500 525);
PAINT GREEN (3500 525);
DISPLAY INVISIBLE (3500 525);
FORCEPROP 1 LAST BODY_TYPE PLUMBING
J 0
(3380 532);
DISPLAY 0.340426 (3380 532);
PAINT GREEN (3380 532);
DISPLAY INVISIBLE (3380 532);
FORCEPROP 1 LAST HDL_POWER GND
J 0
(3425 725);
DISPLAY 0.893617 (3425 725);
PAINT GREEN (3425 725);
DISPLAY INVISIBLE (3425 725);
FORCEADD CAP_A..1
(2600 975);
FORCEPROP 0 LAST BOM_SS 078.1061T.M001
J 0
(2588 668);
DISPLAY 0.638298 (2588 668);
PAINT BROWN (2588 668);
DISPLAY BOTH (2588 668);
FORCEPROP 0 LAST GROUP PWR_MLCC_CAP
J 0
(2656 737);
DISPLAY 0.638298 (2656 737);
PAINT BROWN (2656 737);
DISPLAY BOTH (2656 737);
FORCEPROP 1 LAST PACK_TYPE 0603V
J 0
(2650 775);
DISPLAY 0.617021 (2650 775);
PAINT SKYBLUE (2650 775);
FORCEPROP 1 LAST MATERIAL X5R
J 0
(2650 875);
DISPLAY 0.617021 (2650 875);
PAINT SKYBLUE (2650 875);
FORCEPROP 1 LAST VALUE 47UF
J 0
(2650 1025);
DISPLAY 0.617021 (2650 1025);
PAINT SKYBLUE (2650 1025);
FORCEPROP 1 LAST VOLTAGE 4V
J 0
(2650 975);
DISPLAY 0.617021 (2650 975);
PAINT SKYBLUE (2650 975);
FORCEPROP 1 LAST TOLERANCE 20%
J 0
(2650 925);
DISPLAY 0.617021 (2650 925);
PAINT SKYBLUE (2650 925);
FORCEPROP 1 LAST LOCATION C8T4
J 0
(2650 1075);
DISPLAY 0.617021 (2650 1075);
PAINT AQUA (2650 1075);
FORCEPROP 1 LASTPIN (2600 1075) $PN 1
J 0
(2610 1055);
DISPLAY 0.617021 (2610 1055);
PAINT ORANGE (2610 1055);
FORCEPROP 1 LAST PART_NUMBER 602433-106
J 0
(2650 825);
DISPLAY 0.617021 (2650 825);
PAINT BLUE (2650 825);
FORCEPROP 1 LASTPIN (2600 875) $PN 2
J 0
(2610 855);
DISPLAY 0.617021 (2610 855);
PAINT ORANGE (2610 855);
FORCEPROP 2 LAST CDS_LIB dev_discrete
J 0
(2600 975);
PAINT ORANGE (2600 975);
DISPLAY INVISIBLE (2600 975);
FORCEPROP 2 LAST CDS_LOCATION C8T4
J 0
(2650 1075);
DISPLAY 0.617021 (2650 1075);
PAINT AQUA (2650 1075);
DISPLAY INVISIBLE (2650 1075);
FORCEPROP 1 LAST PATH I196
J 0
(2650 1125);
DISPLAY 0.978723 (2650 1125);
PAINT WHITE (2650 1125);
DISPLAY INVISIBLE (2650 1125);
FORCEPROP 2 LAST CDS_SEC 1
J 0
(2650 1125);
PAINT ORANGE (2650 1125);
DISPLAY INVISIBLE (2650 1125);
FORCEPROP 2 LAST SEC 1
J 0
(2650 1175);
DISPLAY 0.680851 (2650 1175);
PAINT MONO (2650 1175);
DISPLAY INVISIBLE (2650 1175);
FORCEPROP 2 LAST SEC_TYPE 0603V
J 0
(2650 1175);
DISPLAY 1.021277 (2650 1175);
PAINT ORANGE (2650 1175);
DISPLAY INVISIBLE (2650 1175);
FORCEADD CAP_A..1
(2950 975);
FORCEPROP 0 LAST GROUP PWR_MLCC_CAP
J 0
(3006 687);
DISPLAY 0.638298 (3006 687);
PAINT BROWN (3006 687);
DISPLAY BOTH (3006 687);
FORCEPROP 0 LAST BOM_SS NOPOP
J 0
(3013 618);
DISPLAY 0.638298 (3013 618);
PAINT BROWN (3013 618);
DISPLAY BOTH (3013 618);
FORCEPROP 1 LAST VALUE 47UF
J 0
(3000 1025);
DISPLAY 0.617021 (3000 1025);
PAINT SKYBLUE (3000 1025);
FORCEPROP 1 LAST VOLTAGE 4V
J 0
(3000 975);
DISPLAY 0.617021 (3000 975);
PAINT SKYBLUE (3000 975);
FORCEPROP 1 LAST MATERIAL X5R
J 0
(3000 875);
DISPLAY 0.617021 (3000 875);
PAINT SKYBLUE (3000 875);
FORCEPROP 1 LAST PACK_TYPE 0603V
J 0
(3000 775);
DISPLAY 0.617021 (3000 775);
PAINT SKYBLUE (3000 775);
FORCEPROP 1 LAST LOCATION C2G8
J 0
(3000 1075);
DISPLAY 0.617021 (3000 1075);
PAINT AQUA (3000 1075);
FORCEPROP 1 LASTPIN (2950 875) $PN 2
J 0
(2960 855);
DISPLAY 0.617021 (2960 855);
PAINT ORANGE (2960 855);
FORCEPROP 1 LASTPIN (2950 1075) $PN 1
J 0
(2960 1055);
DISPLAY 0.617021 (2960 1055);
PAINT ORANGE (2960 1055);
FORCEPROP 1 LAST PART_NUMBER 602433-106
J 0
(3000 825);
DISPLAY 0.617021 (3000 825);
PAINT BLUE (3000 825);
FORCEPROP 1 LAST TOLERANCE 20%
J 0
(3000 925);
DISPLAY 0.617021 (3000 925);
PAINT SKYBLUE (3000 925);
FORCEPROP 2 LAST CDS_LIB dev_discrete
J 0
(2950 975);
PAINT ORANGE (2950 975);
DISPLAY INVISIBLE (2950 975);
FORCEPROP 2 LAST CDS_LOCATION C2G8
J 0
(3000 1075);
DISPLAY 0.617021 (3000 1075);
PAINT AQUA (3000 1075);
DISPLAY INVISIBLE (3000 1075);
FORCEPROP 2 LAST CDS_SEC 1
J 0
(3000 1125);
PAINT ORANGE (3000 1125);
DISPLAY INVISIBLE (3000 1125);
FORCEPROP 2 LAST SEC_TYPE 0603V
J 0
(3000 1175);
DISPLAY 1.021277 (3000 1175);
PAINT ORANGE (3000 1175);
DISPLAY INVISIBLE (3000 1175);
FORCEPROP 2 LAST SEC 1
J 0
(3000 1175);
DISPLAY 0.680851 (3000 1175);
PAINT MONO (3000 1175);
DISPLAY INVISIBLE (3000 1175);
FORCEPROP 1 LAST PATH I197
J 0
(3000 1125);
DISPLAY 0.978723 (3000 1125);
PAINT WHITE (3000 1125);
DISPLAY INVISIBLE (3000 1125);
FORCEADD CAP_A..1
(3350 975);
FORCEPROP 0 LAST GROUP PWR_MLCC_CAP
J 0
(3406 737);
DISPLAY 0.638298 (3406 737);
PAINT BROWN (3406 737);
DISPLAY BOTH (3406 737);
FORCEPROP 0 LAST BOM_SS NOPOP
J 0
(3513 693);
DISPLAY 0.638298 (3513 693);
PAINT BROWN (3513 693);
DISPLAY BOTH (3513 693);
FORCEPROP 1 LAST PACK_TYPE 0603V
J 0
(3400 775);
DISPLAY 0.617021 (3400 775);
PAINT SKYBLUE (3400 775);
FORCEPROP 1 LASTPIN (3350 875) $PN 2
J 0
(3360 855);
DISPLAY 0.617021 (3360 855);
PAINT ORANGE (3360 855);
FORCEPROP 1 LAST MATERIAL X5R
J 0
(3400 875);
DISPLAY 0.617021 (3400 875);
PAINT SKYBLUE (3400 875);
FORCEPROP 1 LAST TOLERANCE 20%
J 0
(3400 925);
DISPLAY 0.617021 (3400 925);
PAINT SKYBLUE (3400 925);
FORCEPROP 1 LASTPIN (3350 1075) $PN 1
J 0
(3360 1055);
DISPLAY 0.617021 (3360 1055);
PAINT ORANGE (3360 1055);
FORCEPROP 1 LAST VALUE 47UF
J 0
(3400 1025);
DISPLAY 0.617021 (3400 1025);
PAINT SKYBLUE (3400 1025);
FORCEPROP 1 LAST VOLTAGE 4V
J 0
(3400 975);
DISPLAY 0.617021 (3400 975);
PAINT SKYBLUE (3400 975);
FORCEPROP 1 LAST LOCATION C8T2
J 0
(3400 1075);
DISPLAY 0.617021 (3400 1075);
PAINT AQUA (3400 1075);
FORCEPROP 1 LAST PART_NUMBER 602433-106
J 0
(3400 825);
DISPLAY 0.617021 (3400 825);
PAINT BLUE (3400 825);
FORCEPROP 2 LAST CDS_LIB dev_discrete
J 0
(3350 975);
PAINT ORANGE (3350 975);
DISPLAY INVISIBLE (3350 975);
FORCEPROP 1 LAST PATH I198
J 0
(3400 1125);
DISPLAY 0.978723 (3400 1125);
PAINT WHITE (3400 1125);
DISPLAY INVISIBLE (3400 1125);
FORCEPROP 2 LAST SEC 1
J 0
(3400 1175);
DISPLAY 0.680851 (3400 1175);
PAINT MONO (3400 1175);
DISPLAY INVISIBLE (3400 1175);
FORCEPROP 2 LAST SEC_TYPE 0603V
J 0
(3400 1175);
DISPLAY 1.021277 (3400 1175);
PAINT ORANGE (3400 1175);
DISPLAY INVISIBLE (3400 1175);
FORCEPROP 2 LAST CDS_SEC 1
J 0
(3400 1125);
PAINT ORANGE (3400 1125);
DISPLAY INVISIBLE (3400 1125);
FORCEPROP 2 LAST CDS_LOCATION C8T2
J 0
(3400 1075);
DISPLAY 0.617021 (3400 1075);
PAINT AQUA (3400 1075);
DISPLAY INVISIBLE (3400 1075);
FORCEADD CAP_A..1
(2550 1725);
FORCEPROP 0 LAST BOM_SS NOPOP
J 0
(2613 1418);
DISPLAY 0.638298 (2613 1418);
PAINT BROWN (2613 1418);
DISPLAY BOTH (2613 1418);
FORCEPROP 0 LAST GROUP PWR_MLCC_CAP
J 0
(2606 1487);
DISPLAY 0.638298 (2606 1487);
PAINT BROWN (2606 1487);
DISPLAY BOTH (2606 1487);
FORCEPROP 1 LAST PART_NUMBER 602433-106
J 0
(2600 1575);
DISPLAY 0.617021 (2600 1575);
PAINT BLUE (2600 1575);
FORCEPROP 1 LAST LOCATION C8U13
J 0
(2600 1825);
DISPLAY 0.617021 (2600 1825);
PAINT AQUA (2600 1825);
FORCEPROP 1 LASTPIN (2550 1825) $PN 1
J 0
(2560 1805);
DISPLAY 0.617021 (2560 1805);
PAINT ORANGE (2560 1805);
FORCEPROP 1 LASTPIN (2550 1625) $PN 2
J 0
(2560 1605);
DISPLAY 0.617021 (2560 1605);
PAINT ORANGE (2560 1605);
FORCEPROP 1 LAST VALUE 47UF
J 0
(2600 1775);
DISPLAY 0.617021 (2600 1775);
PAINT SKYBLUE (2600 1775);
FORCEPROP 1 LAST VOLTAGE 4V
J 0
(2600 1725);
DISPLAY 0.617021 (2600 1725);
PAINT SKYBLUE (2600 1725);
FORCEPROP 1 LAST MATERIAL X5R
J 0
(2600 1625);
DISPLAY 0.617021 (2600 1625);
PAINT SKYBLUE (2600 1625);
FORCEPROP 1 LAST TOLERANCE 20%
J 0
(2600 1675);
DISPLAY 0.617021 (2600 1675);
PAINT SKYBLUE (2600 1675);
FORCEPROP 1 LAST PACK_TYPE 0603V
J 0
(2600 1525);
DISPLAY 0.617021 (2600 1525);
PAINT SKYBLUE (2600 1525);
FORCEPROP 2 LAST CDS_LIB dev_discrete
J 0
(2550 1725);
PAINT ORANGE (2550 1725);
DISPLAY INVISIBLE (2550 1725);
FORCEPROP 2 LAST CDS_LOCATION C8U13
J 0
(2600 1825);
DISPLAY 0.617021 (2600 1825);
PAINT AQUA (2600 1825);
DISPLAY INVISIBLE (2600 1825);
FORCEPROP 2 LAST CDS_SEC 1
J 0
(2600 1875);
PAINT ORANGE (2600 1875);
DISPLAY INVISIBLE (2600 1875);
FORCEPROP 2 LAST SEC_TYPE 0603V
J 0
(2600 1925);
DISPLAY 1.021277 (2600 1925);
PAINT ORANGE (2600 1925);
DISPLAY INVISIBLE (2600 1925);
FORCEPROP 2 LAST SEC 1
J 0
(2600 1925);
DISPLAY 0.680851 (2600 1925);
PAINT MONO (2600 1925);
DISPLAY INVISIBLE (2600 1925);
FORCEPROP 1 LAST PATH I199
J 0
(2600 1875);
DISPLAY 0.978723 (2600 1875);
PAINT WHITE (2600 1875);
DISPLAY INVISIBLE (2600 1875);
FORCEADD CAP_A..1
(2900 1725);
FORCEPROP 0 LAST GROUP PWR_MLCC_CAP
J 0
(2956 1437);
DISPLAY 0.638298 (2956 1437);
PAINT BROWN (2956 1437);
DISPLAY BOTH (2956 1437);
FORCEPROP 0 LAST BOM_SS NOPOP
J 0
(2963 1393);
DISPLAY 0.638298 (2963 1393);
PAINT BROWN (2963 1393);
DISPLAY BOTH (2963 1393);
FORCEPROP 1 LASTPIN (2900 1825) $PN 1
J 0
(2910 1805);
DISPLAY 0.617021 (2910 1805);
PAINT ORANGE (2910 1805);
FORCEPROP 1 LAST TOLERANCE 20%
J 0
(2950 1675);
DISPLAY 0.617021 (2950 1675);
PAINT SKYBLUE (2950 1675);
FORCEPROP 1 LAST PACK_TYPE 0603V
J 0
(2950 1525);
DISPLAY 0.617021 (2950 1525);
PAINT SKYBLUE (2950 1525);
FORCEPROP 1 LAST VOLTAGE 4V
J 0
(2950 1725);
DISPLAY 0.617021 (2950 1725);
PAINT SKYBLUE (2950 1725);
FORCEPROP 1 LASTPIN (2900 1625) $PN 2
J 0
(2910 1605);
DISPLAY 0.617021 (2910 1605);
PAINT ORANGE (2910 1605);
FORCEPROP 1 LAST LOCATION C2G15
J 0
(2950 1825);
DISPLAY 0.617021 (2950 1825);
PAINT AQUA (2950 1825);
FORCEPROP 1 LAST VALUE 47UF
J 0
(2950 1775);
DISPLAY 0.617021 (2950 1775);
PAINT SKYBLUE (2950 1775);
FORCEPROP 1 LAST MATERIAL X5R
J 0
(2950 1625);
DISPLAY 0.617021 (2950 1625);
PAINT SKYBLUE (2950 1625);
FORCEPROP 1 LAST PART_NUMBER 602433-106
J 0
(2950 1575);
DISPLAY 0.617021 (2950 1575);
PAINT BLUE (2950 1575);
FORCEPROP 2 LAST CDS_LIB dev_discrete
J 0
(2900 1725);
PAINT ORANGE (2900 1725);
DISPLAY INVISIBLE (2900 1725);
FORCEPROP 2 LAST CDS_LOCATION C2G15
J 0
(2950 1825);
DISPLAY 0.617021 (2950 1825);
PAINT AQUA (2950 1825);
DISPLAY INVISIBLE (2950 1825);
FORCEPROP 2 LAST CDS_SEC 1
J 0
(2950 1875);
PAINT ORANGE (2950 1875);
DISPLAY INVISIBLE (2950 1875);
FORCEPROP 2 LAST SEC_TYPE 0603V
J 0
(2950 1925);
DISPLAY 1.021277 (2950 1925);
PAINT ORANGE (2950 1925);
DISPLAY INVISIBLE (2950 1925);
FORCEPROP 2 LAST SEC 1
J 0
(2950 1925);
DISPLAY 0.680851 (2950 1925);
PAINT MONO (2950 1925);
DISPLAY INVISIBLE (2950 1925);
FORCEPROP 1 LAST PATH I200
J 0
(2950 1875);
DISPLAY 0.978723 (2950 1875);
PAINT WHITE (2950 1875);
DISPLAY INVISIBLE (2950 1875);
FORCEADD CAP_A..1
(3300 1725);
FORCEPROP 0 LAST BOM_SS NOPOP
J 0
(3363 1393);
DISPLAY 0.638298 (3363 1393);
PAINT BROWN (3363 1393);
DISPLAY BOTH (3363 1393);
FORCEPROP 0 LAST GROUP PWR_MLCC_CAP
J 0
(3356 1487);
DISPLAY 0.638298 (3356 1487);
PAINT BROWN (3356 1487);
DISPLAY BOTH (3356 1487);
FORCEPROP 1 LAST PACK_TYPE 0603V
J 0
(3350 1525);
DISPLAY 0.617021 (3350 1525);
PAINT SKYBLUE (3350 1525);
FORCEPROP 1 LASTPIN (3300 1825) $PN 1
J 0
(3310 1805);
DISPLAY 0.617021 (3310 1805);
PAINT ORANGE (3310 1805);
FORCEPROP 1 LASTPIN (3300 1625) $PN 2
J 0
(3310 1605);
DISPLAY 0.617021 (3310 1605);
PAINT ORANGE (3310 1605);
FORCEPROP 1 LAST LOCATION C2F1
J 0
(3350 1825);
DISPLAY 0.617021 (3350 1825);
PAINT AQUA (3350 1825);
FORCEPROP 1 LAST VALUE 47UF
J 0
(3350 1775);
DISPLAY 0.617021 (3350 1775);
PAINT SKYBLUE (3350 1775);
FORCEPROP 1 LAST TOLERANCE 20%
J 0
(3350 1675);
DISPLAY 0.617021 (3350 1675);
PAINT SKYBLUE (3350 1675);
FORCEPROP 1 LAST VOLTAGE 4V
J 0
(3350 1725);
DISPLAY 0.617021 (3350 1725);
PAINT SKYBLUE (3350 1725);
FORCEPROP 1 LAST MATERIAL X5R
J 0
(3350 1625);
DISPLAY 0.617021 (3350 1625);
PAINT SKYBLUE (3350 1625);
FORCEPROP 1 LAST PART_NUMBER 602433-106
J 0
(3350 1575);
DISPLAY 0.617021 (3350 1575);
PAINT BLUE (3350 1575);
FORCEPROP 2 LAST CDS_LIB dev_discrete
J 0
(3300 1725);
PAINT ORANGE (3300 1725);
DISPLAY INVISIBLE (3300 1725);
FORCEPROP 2 LAST CDS_LOCATION C2F1
J 0
(3350 1825);
DISPLAY 0.617021 (3350 1825);
PAINT AQUA (3350 1825);
DISPLAY INVISIBLE (3350 1825);
FORCEPROP 2 LAST CDS_SEC 1
J 0
(3350 1875);
PAINT ORANGE (3350 1875);
DISPLAY INVISIBLE (3350 1875);
FORCEPROP 2 LAST SEC_TYPE 0603V
J 0
(3350 1925);
DISPLAY 1.021277 (3350 1925);
PAINT ORANGE (3350 1925);
DISPLAY INVISIBLE (3350 1925);
FORCEPROP 2 LAST SEC 1
J 0
(3350 1925);
DISPLAY 0.680851 (3350 1925);
PAINT MONO (3350 1925);
DISPLAY INVISIBLE (3350 1925);
FORCEPROP 1 LAST PATH I201
J 0
(3350 1875);
DISPLAY 0.978723 (3350 1875);
PAINT WHITE (3350 1875);
DISPLAY INVISIBLE (3350 1875);
FORCEADD CAP_A..1
(3650 1725);
FORCEPROP 1 LAST PART_NUMBER 602433-106
J 0
(3700 1575);
DISPLAY 0.617021 (3700 1575);
PAINT BLUE (3700 1575);
FORCEPROP 0 LAST GROUP PWR_MLCC_CAP
J 0
(3706 1437);
DISPLAY 0.638298 (3706 1437);
PAINT BROWN (3706 1437);
DISPLAY BOTH (3706 1437);
FORCEPROP 0 LAST BOM_SS NOPOP
J 0
(3688 1368);
DISPLAY 0.638298 (3688 1368);
PAINT BROWN (3688 1368);
DISPLAY BOTH (3688 1368);
FORCEPROP 1 LAST PACK_TYPE 0603V
J 0
(3700 1525);
DISPLAY 0.617021 (3700 1525);
PAINT SKYBLUE (3700 1525);
FORCEPROP 1 LAST MATERIAL X5R
J 0
(3700 1625);
DISPLAY 0.617021 (3700 1625);
PAINT SKYBLUE (3700 1625);
FORCEPROP 1 LAST VOLTAGE 4V
J 0
(3700 1725);
DISPLAY 0.617021 (3700 1725);
PAINT SKYBLUE (3700 1725);
FORCEPROP 1 LAST TOLERANCE 20%
J 0
(3700 1675);
DISPLAY 0.617021 (3700 1675);
PAINT SKYBLUE (3700 1675);
FORCEPROP 1 LAST VALUE 47UF
J 0
(3700 1775);
DISPLAY 0.617021 (3700 1775);
PAINT SKYBLUE (3700 1775);
FORCEPROP 1 LASTPIN (3650 1825) $PN 1
J 0
(3660 1805);
DISPLAY 0.617021 (3660 1805);
PAINT ORANGE (3660 1805);
FORCEPROP 1 LAST LOCATION C8T1
J 0
(3700 1825);
DISPLAY 0.617021 (3700 1825);
PAINT AQUA (3700 1825);
FORCEPROP 1 LASTPIN (3650 1625) $PN 2
J 0
(3660 1605);
DISPLAY 0.617021 (3660 1605);
PAINT ORANGE (3660 1605);
FORCEPROP 2 LAST CDS_LIB dev_discrete
J 0
(3650 1725);
PAINT ORANGE (3650 1725);
DISPLAY INVISIBLE (3650 1725);
FORCEPROP 1 LAST PATH I202
J 0
(3700 1875);
DISPLAY 0.978723 (3700 1875);
PAINT WHITE (3700 1875);
DISPLAY INVISIBLE (3700 1875);
FORCEPROP 2 LAST SEC 1
J 0
(3700 1925);
DISPLAY 0.680851 (3700 1925);
PAINT MONO (3700 1925);
DISPLAY INVISIBLE (3700 1925);
FORCEPROP 2 LAST SEC_TYPE 0603V
J 0
(3700 1925);
DISPLAY 1.021277 (3700 1925);
PAINT ORANGE (3700 1925);
DISPLAY INVISIBLE (3700 1925);
FORCEPROP 2 LAST CDS_SEC 1
J 0
(3700 1875);
PAINT ORANGE (3700 1875);
DISPLAY INVISIBLE (3700 1875);
FORCEPROP 2 LAST CDS_LOCATION C8T1
J 0
(3700 1825);
DISPLAY 0.617021 (3700 1825);
PAINT AQUA (3700 1825);
DISPLAY INVISIBLE (3700 1825);
FORCEADD CAP_A..1
(4000 1725);
FORCEPROP 0 LAST GROUP PWR_MLCC_CAP
J 0
(4056 1487);
DISPLAY 0.638298 (4056 1487);
PAINT BROWN (4056 1487);
DISPLAY BOTH (4056 1487);
FORCEPROP 1 LAST PACK_TYPE 0603V
J 0
(4050 1525);
DISPLAY 0.617021 (4050 1525);
PAINT SKYBLUE (4050 1525);
FORCEPROP 1 LAST PART_NUMBER 602433-106
J 0
(4050 1575);
DISPLAY 0.617021 (4050 1575);
PAINT BLUE (4050 1575);
FORCEPROP 1 LASTPIN (4000 1625) $PN 2
J 0
(4010 1605);
DISPLAY 0.617021 (4010 1605);
PAINT ORANGE (4010 1605);
FORCEPROP 1 LAST LOCATION C8U9
J 0
(4050 1825);
DISPLAY 0.617021 (4050 1825);
PAINT AQUA (4050 1825);
FORCEPROP 1 LAST VOLTAGE 4V
J 0
(4050 1725);
DISPLAY 0.617021 (4050 1725);
PAINT SKYBLUE (4050 1725);
FORCEPROP 1 LASTPIN (4000 1825) $PN 1
J 0
(4010 1805);
DISPLAY 0.617021 (4010 1805);
PAINT ORANGE (4010 1805);
FORCEPROP 1 LAST VALUE 47UF
J 0
(4050 1775);
DISPLAY 0.617021 (4050 1775);
PAINT SKYBLUE (4050 1775);
FORCEPROP 1 LAST TOLERANCE 20%
J 0
(4050 1675);
DISPLAY 0.617021 (4050 1675);
PAINT SKYBLUE (4050 1675);
FORCEPROP 1 LAST MATERIAL X5R
J 0
(4050 1625);
DISPLAY 0.617021 (4050 1625);
PAINT SKYBLUE (4050 1625);
FORCEPROP 0 LAST BOM_SS NOPOP
J 0
(4038 1393);
DISPLAY 0.638298 (4038 1393);
PAINT BROWN (4038 1393);
DISPLAY BOTH (4038 1393);
FORCEPROP 2 LAST CDS_LIB dev_discrete
J 0
(4000 1725);
PAINT ORANGE (4000 1725);
DISPLAY INVISIBLE (4000 1725);
FORCEPROP 1 LAST PATH I203
J 0
(4050 1875);
DISPLAY 0.978723 (4050 1875);
PAINT WHITE (4050 1875);
DISPLAY INVISIBLE (4050 1875);
FORCEPROP 2 LAST SEC 1
J 0
(4050 1925);
DISPLAY 0.680851 (4050 1925);
PAINT MONO (4050 1925);
DISPLAY INVISIBLE (4050 1925);
FORCEPROP 2 LAST SEC_TYPE 0603V
J 0
(4050 1925);
DISPLAY 1.021277 (4050 1925);
PAINT ORANGE (4050 1925);
DISPLAY INVISIBLE (4050 1925);
FORCEPROP 2 LAST CDS_SEC 1
J 0
(4050 1875);
PAINT ORANGE (4050 1875);
DISPLAY INVISIBLE (4050 1875);
FORCEPROP 2 LAST CDS_LOCATION C8U9
J 0
(4050 1825);
DISPLAY 0.617021 (4050 1825);
PAINT AQUA (4050 1825);
DISPLAY INVISIBLE (4050 1825);
FORCEADD CAP_A..1
(4400 1725);
FORCEPROP 0 LAST GROUP PWR_MLCC_CAP
J 0
(4456 1437);
DISPLAY 0.638298 (4456 1437);
PAINT BROWN (4456 1437);
DISPLAY BOTH (4456 1437);
FORCEPROP 1 LAST PART_NUMBER 602433-106
J 0
(4450 1575);
DISPLAY 0.617021 (4450 1575);
PAINT BLUE (4450 1575);
FORCEPROP 1 LAST VALUE 47UF
J 0
(4450 1775);
DISPLAY 0.617021 (4450 1775);
PAINT SKYBLUE (4450 1775);
FORCEPROP 1 LAST PACK_TYPE 0603V
J 0
(4450 1525);
DISPLAY 0.617021 (4450 1525);
PAINT SKYBLUE (4450 1525);
FORCEPROP 1 LAST TOLERANCE 20%
J 0
(4450 1675);
DISPLAY 0.617021 (4450 1675);
PAINT SKYBLUE (4450 1675);
FORCEPROP 1 LAST VOLTAGE 4V
J 0
(4450 1725);
DISPLAY 0.617021 (4450 1725);
PAINT SKYBLUE (4450 1725);
FORCEPROP 1 LAST MATERIAL X5R
J 0
(4450 1625);
DISPLAY 0.617021 (4450 1625);
PAINT SKYBLUE (4450 1625);
FORCEPROP 1 LASTPIN (4400 1625) $PN 2
J 0
(4410 1605);
DISPLAY 0.617021 (4410 1605);
PAINT ORANGE (4410 1605);
FORCEPROP 1 LAST LOCATION C8T11
J 0
(4450 1825);
DISPLAY 0.617021 (4450 1825);
PAINT AQUA (4450 1825);
FORCEPROP 1 LASTPIN (4400 1825) $PN 1
J 0
(4410 1805);
DISPLAY 0.617021 (4410 1805);
PAINT ORANGE (4410 1805);
FORCEPROP 0 LAST BOM_SS NOPOP
J 0
(4438 1368);
DISPLAY 0.638298 (4438 1368);
PAINT BROWN (4438 1368);
DISPLAY BOTH (4438 1368);
FORCEPROP 2 LAST CDS_LIB dev_discrete
J 0
(4400 1725);
PAINT ORANGE (4400 1725);
DISPLAY INVISIBLE (4400 1725);
FORCEPROP 2 LAST CDS_LOCATION C8T11
J 0
(4450 1825);
DISPLAY 0.617021 (4450 1825);
PAINT AQUA (4450 1825);
DISPLAY INVISIBLE (4450 1825);
FORCEPROP 2 LAST CDS_SEC 1
J 0
(4450 1875);
PAINT ORANGE (4450 1875);
DISPLAY INVISIBLE (4450 1875);
FORCEPROP 2 LAST SEC_TYPE 0603V
J 0
(4450 1925);
DISPLAY 1.021277 (4450 1925);
PAINT ORANGE (4450 1925);
DISPLAY INVISIBLE (4450 1925);
FORCEPROP 2 LAST SEC 1
J 0
(4450 1925);
DISPLAY 0.680851 (4450 1925);
PAINT MONO (4450 1925);
DISPLAY INVISIBLE (4450 1925);
FORCEPROP 1 LAST PATH I204
J 0
(4450 1875);
DISPLAY 0.978723 (4450 1875);
PAINT WHITE (4450 1875);
DISPLAY INVISIBLE (4450 1875);
FORCEADD PVDDQ_GHJ..1
(-1450 3375);
FORCEPROP 3 LASTPIN (-1450 3325) SIG_NAME PVDDQ_GHJ\g
J 0
(-1440 3335);
DISPLAY 0.659574 (-1440 3335);
PAINT MONO (-1440 3335);
DISPLAY INVISIBLE (-1440 3335);
FORCEPROP 1 LAST PATH I205
J 0
(-1400 3400);
DISPLAY 0.872340 (-1400 3400);
PAINT AQUA (-1400 3400);
DISPLAY INVISIBLE (-1400 3400);
FORCEPROP 2 LAST BOM_COST MEM_VRD_PVPP_AB
J 0
(-1400 3475);
PAINT MONO (-1400 3475);
DISPLAY INVISIBLE (-1400 3475);
FORCEPROP 2 LAST ROOM VDDQ_GHJ_PWR_VR
J 0
(-1225 3475);
PAINT ORANGE (-1225 3475);
DISPLAY INVISIBLE (-1225 3475);
FORCEPROP 2 LAST CDS_LIB mstr_symbols
J 0
(-1450 3375);
PAINT ORANGE (-1450 3375);
DISPLAY INVISIBLE (-1450 3375);
FORCEPROP 1 LAST VOLTAGE 1.2V
J 0
(-1495 3332);
DISPLAY 0.340426 (-1495 3332);
PAINT SKYBLUE (-1495 3332);
DISPLAY INVISIBLE (-1495 3332);
FORCEPROP 1 LAST BODY_TYPE PLUMBING
J 0
(-1495 3332);
DISPLAY 0.340426 (-1495 3332);
PAINT GREEN (-1495 3332);
DISPLAY INVISIBLE (-1495 3332);
FORCEPROP 1 LAST HDL_POWER PVDDQ_GHJ
J 1
(-1450 3425);
DISPLAY 0.872340 (-1450 3425);
PAINT GREEN (-1450 3425);
DISPLAY INVISIBLE (-1450 3425);
FORCEADD GND..1
(-2325 2625);
FORCEPROP 3 LASTPIN (-2325 2675) SIG_NAME GND\g
J 0
(-2315 2685);
DISPLAY 0.659574 (-2315 2685);
PAINT MONO (-2315 2685);
DISPLAY INVISIBLE (-2315 2685);
FORCEPROP 2 LAST BOM_COST MEM_VRD_PVDDQ_CD
J 0
(-2650 2700);
PAINT MONO (-2650 2700);
DISPLAY INVISIBLE (-2650 2700);
FORCEPROP 2 LAST ROOM VDDQ_ABC_PWR_VR
J 0
(-2875 2700);
PAINT ORANGE (-2875 2700);
DISPLAY INVISIBLE (-2875 2700);
FORCEPROP 2 LAST CDS_LIB mstr_symbols
J 0
(-2325 2625);
PAINT ORANGE (-2325 2625);
DISPLAY INVISIBLE (-2325 2625);
FORCEPROP 1 LAST VOLTAGE 0
J 0
(-2325 2625);
PAINT SKYBLUE (-2325 2625);
DISPLAY INVISIBLE (-2325 2625);
FORCEPROP 1 LAST PATH I206
J 0
(-2250 2625);
DISPLAY 0.872340 (-2250 2625);
PAINT AQUA (-2250 2625);
DISPLAY INVISIBLE (-2250 2625);
FORCEPROP 1 LAST SIZE 1B
J 0
(-2250 2575);
DISPLAY 0.893617 (-2250 2575);
PAINT GREEN (-2250 2575);
DISPLAY INVISIBLE (-2250 2575);
FORCEPROP 1 LAST BODY_TYPE PLUMBING
J 0
(-2370 2582);
DISPLAY 0.340426 (-2370 2582);
PAINT GREEN (-2370 2582);
DISPLAY INVISIBLE (-2370 2582);
FORCEPROP 1 LAST HDL_POWER GND
J 0
(-2325 2775);
DISPLAY 0.893617 (-2325 2775);
PAINT GREEN (-2325 2775);
DISPLAY INVISIBLE (-2325 2775);
FORCEADD PVDDQ_GHJ..1
(-2275 500);
FORCEPROP 3 LASTPIN (-2275 450) SIG_NAME PVDDQ_GHJ\g
J 0
(-2265 460);
DISPLAY 0.659574 (-2265 460);
PAINT MONO (-2265 460);
DISPLAY INVISIBLE (-2265 460);
FORCEPROP 1 LAST VOLTAGE 1.2V
J 0
(-2320 457);
DISPLAY 0.340426 (-2320 457);
PAINT SKYBLUE (-2320 457);
DISPLAY INVISIBLE (-2320 457);
FORCEPROP 2 LAST CDS_LIB mstr_symbols
J 0
(-2275 500);
PAINT ORANGE (-2275 500);
DISPLAY INVISIBLE (-2275 500);
FORCEPROP 1 LAST PATH I222
J 0
(-2225 525);
DISPLAY 0.872340 (-2225 525);
PAINT AQUA (-2225 525);
DISPLAY INVISIBLE (-2225 525);
FORCEPROP 1 LAST BODY_TYPE PLUMBING
J 0
(-2320 457);
DISPLAY 0.340426 (-2320 457);
PAINT GREEN (-2320 457);
DISPLAY INVISIBLE (-2320 457);
FORCEPROP 1 LAST HDL_POWER PVDDQ_GHJ
J 1
(-2275 550);
DISPLAY 0.872340 (-2275 550);
PAINT GREEN (-2275 550);
DISPLAY INVISIBLE (-2275 550);
FORCEADD GND..1
(-2275 -75);
FORCEPROP 3 LASTPIN (-2275 -25) SIG_NAME GND\g
J 0
(-2265 -15);
DISPLAY 0.659574 (-2265 -15);
PAINT MONO (-2265 -15);
DISPLAY INVISIBLE (-2265 -15);
FORCEPROP 1 LAST SIZE 1B
J 0
(-2200 -125);
DISPLAY 1.723404 (-2200 -125);
PAINT GREEN (-2200 -125);
DISPLAY INVISIBLE (-2200 -125);
FORCEPROP 1 LAST VOLTAGE 0
J 0
(-2275 -75);
PAINT SKYBLUE (-2275 -75);
DISPLAY INVISIBLE (-2275 -75);
FORCEPROP 2 LAST CDS_LIB mstr_symbols
J 0
(-2275 -75);
PAINT ORANGE (-2275 -75);
DISPLAY INVISIBLE (-2275 -75);
FORCEPROP 1 LAST PATH I224
J 0
(-2200 -75);
DISPLAY 0.872340 (-2200 -75);
PAINT AQUA (-2200 -75);
DISPLAY INVISIBLE (-2200 -75);
FORCEPROP 2 LAST BOM_COST PROC_VRD_VCCIN_CPU0
J 0
(-2650 0);
DISPLAY 1.446809 (-2650 0);
PAINT MONO (-2650 0);
DISPLAY INVISIBLE (-2650 0);
FORCEPROP 2 LAST ROOM VDDQ_ABC_PWR_VR
J 0
(-2825 0);
DISPLAY 1.936170 (-2825 0);
PAINT ORANGE (-2825 0);
DISPLAY INVISIBLE (-2825 0);
FORCEPROP 1 LAST BODY_TYPE PLUMBING
J 0
(-2320 -118);
DISPLAY 0.340426 (-2320 -118);
PAINT GREEN (-2320 -118);
DISPLAY INVISIBLE (-2320 -118);
FORCEPROP 1 LAST HDL_POWER GND
J 0
(-2275 75);
DISPLAY 1.723404 (-2275 75);
PAINT GREEN (-2275 75);
DISPLAY INVISIBLE (-2275 75);
FORCEADD PVDDQ_GHJ..1
(-2250 -200);
FORCEPROP 3 LASTPIN (-2250 -250) SIG_NAME PVDDQ_GHJ\g
J 0
(-2240 -240);
DISPLAY 0.659574 (-2240 -240);
PAINT MONO (-2240 -240);
DISPLAY INVISIBLE (-2240 -240);
FORCEPROP 1 LAST VOLTAGE 1.2V
J 0
(-2295 -243);
DISPLAY 0.340426 (-2295 -243);
PAINT SKYBLUE (-2295 -243);
DISPLAY INVISIBLE (-2295 -243);
FORCEPROP 2 LAST CDS_LIB mstr_symbols
J 0
(-2250 -200);
PAINT ORANGE (-2250 -200);
DISPLAY INVISIBLE (-2250 -200);
FORCEPROP 1 LAST PATH I240
J 0
(-2200 -175);
DISPLAY 0.872340 (-2200 -175);
PAINT AQUA (-2200 -175);
DISPLAY INVISIBLE (-2200 -175);
FORCEPROP 1 LAST BODY_TYPE PLUMBING
J 0
(-2295 -243);
DISPLAY 0.340426 (-2295 -243);
PAINT GREEN (-2295 -243);
DISPLAY INVISIBLE (-2295 -243);
FORCEPROP 1 LAST HDL_POWER PVDDQ_GHJ
J 1
(-2250 -150);
DISPLAY 0.872340 (-2250 -150);
PAINT GREEN (-2250 -150);
DISPLAY INVISIBLE (-2250 -150);
FORCEADD GND..1
(-2250 -800);
FORCEPROP 3 LASTPIN (-2250 -750) SIG_NAME GND\g
J 0
(-2240 -740);
DISPLAY 0.659574 (-2240 -740);
PAINT MONO (-2240 -740);
DISPLAY INVISIBLE (-2240 -740);
FORCEPROP 1 LAST PATH I242
J 0
(-2175 -800);
DISPLAY 0.872340 (-2175 -800);
PAINT AQUA (-2175 -800);
DISPLAY INVISIBLE (-2175 -800);
FORCEPROP 2 LAST CDS_LIB mstr_symbols
J 0
(-2250 -800);
PAINT ORANGE (-2250 -800);
DISPLAY INVISIBLE (-2250 -800);
FORCEPROP 1 LAST VOLTAGE 0
J 0
(-2250 -800);
PAINT SKYBLUE (-2250 -800);
DISPLAY INVISIBLE (-2250 -800);
FORCEPROP 1 LAST SIZE 1B
J 0
(-2175 -850);
DISPLAY 1.723404 (-2175 -850);
PAINT GREEN (-2175 -850);
DISPLAY INVISIBLE (-2175 -850);
FORCEPROP 2 LAST ROOM VDDQ_ABC_PWR_VR
J 0
(-2800 -725);
DISPLAY 1.936170 (-2800 -725);
PAINT ORANGE (-2800 -725);
DISPLAY INVISIBLE (-2800 -725);
FORCEPROP 2 LAST BOM_COST PROC_VRD_VCCIN_CPU0
J 0
(-2625 -725);
DISPLAY 1.446809 (-2625 -725);
PAINT MONO (-2625 -725);
DISPLAY INVISIBLE (-2625 -725);
FORCEPROP 1 LAST BODY_TYPE PLUMBING
J 0
(-2295 -843);
DISPLAY 0.340426 (-2295 -843);
PAINT GREEN (-2295 -843);
DISPLAY INVISIBLE (-2295 -843);
FORCEPROP 1 LAST HDL_POWER GND
J 0
(-2250 -650);
DISPLAY 1.723404 (-2250 -650);
PAINT GREEN (-2250 -650);
DISPLAY INVISIBLE (-2250 -650);
FORCEADD SHUNT..1
(-250 2325);
FORCEPROP 1 LASTPIN (-400 2325) $PN 1
J 2
(-350 2335);
DISPLAY 0.617021 (-350 2335);
PAINT ORANGE (-350 2335);
FORCEPROP 1 LAST PART_NUMBER N_A
J 0
(-325 2235);
DISPLAY 0.617021 (-325 2235);
PAINT BLUE (-325 2235);
FORCEPROP 1 LASTPIN (-100 2325) $PN 2
J 0
(-140 2335);
DISPLAY 0.617021 (-140 2335);
PAINT ORANGE (-140 2335);
FORCEPROP 1 LAST LOCATION SH7U1
J 0
(-325 2375);
DISPLAY 0.617021 (-325 2375);
PAINT AQUA (-325 2375);
FORCEPROP 1 LAST PIN_SHORT A:B
J 0
(-325 2075);
DISPLAY 1.021277 (-325 2075);
PAINT ORANGE (-325 2075);
DISPLAY INVISIBLE (-325 2075);
FORCEPROP 1 LAST PACK_TYPE SH0201
J 0
(-310 2140);
DISPLAY 0.978723 (-310 2140);
PAINT SKYBLUE (-310 2140);
DISPLAY INVISIBLE (-310 2140);
FORCEPROP 1 LAST MATERIAL EMPTY
J 0
(-325 2190);
DISPLAY 0.978723 (-325 2190);
PAINT RED (-325 2190);
DISPLAY INVISIBLE (-325 2190);
FORCEPROP 0 LAST SEC 1
J 0
(-325 2425);
DISPLAY 0.680851 (-325 2425);
PAINT MONO (-325 2425);
DISPLAY INVISIBLE (-325 2425);
FORCEPROP 1 LAST PATH I243
J 0
(-300 2425);
DISPLAY 0.978723 (-300 2425);
PAINT ORANGE (-300 2425);
DISPLAY INVISIBLE (-300 2425);
FORCEPROP 2 LAST SEC_TYPE SH0201
J 0
(-300 2475);
DISPLAY 1.021277 (-300 2475);
PAINT ORANGE (-300 2475);
DISPLAY INVISIBLE (-300 2475);
FORCEPROP 2 LAST CDS_LIB mstr_misc
J 0
(-250 2325);
PAINT ORANGE (-250 2325);
DISPLAY INVISIBLE (-250 2325);
FORCEADD SHUNT..1
(-275 1875);
FORCEPROP 1 LAST PART_NUMBER N_A
J 0
(-350 1785);
DISPLAY 0.617021 (-350 1785);
PAINT BLUE (-350 1785);
FORCEPROP 1 LASTPIN (-425 1875) $PN 1
J 2
(-375 1885);
DISPLAY 0.617021 (-375 1885);
PAINT ORANGE (-375 1885);
FORCEPROP 1 LAST LOCATION SH7U2
J 0
(-350 1925);
DISPLAY 0.617021 (-350 1925);
PAINT AQUA (-350 1925);
FORCEPROP 1 LASTPIN (-125 1875) $PN 2
J 0
(-165 1885);
DISPLAY 0.617021 (-165 1885);
PAINT ORANGE (-165 1885);
FORCEPROP 1 LAST MATERIAL EMPTY
J 0
(-350 1740);
DISPLAY 0.978723 (-350 1740);
PAINT RED (-350 1740);
DISPLAY INVISIBLE (-350 1740);
FORCEPROP 1 LAST PACK_TYPE SH0201
J 0
(-335 1690);
DISPLAY 0.978723 (-335 1690);
PAINT SKYBLUE (-335 1690);
DISPLAY INVISIBLE (-335 1690);
FORCEPROP 1 LAST PIN_SHORT A:B
J 0
(-350 1625);
DISPLAY 1.021277 (-350 1625);
PAINT ORANGE (-350 1625);
DISPLAY INVISIBLE (-350 1625);
FORCEPROP 2 LAST CDS_LIB mstr_misc
J 0
(-275 1875);
PAINT ORANGE (-275 1875);
DISPLAY INVISIBLE (-275 1875);
FORCEPROP 0 LAST SEC 1
J 0
(-350 1975);
DISPLAY 0.680851 (-350 1975);
PAINT MONO (-350 1975);
DISPLAY INVISIBLE (-350 1975);
FORCEPROP 1 LAST PATH I244
J 0
(-325 1975);
DISPLAY 0.978723 (-325 1975);
PAINT ORANGE (-325 1975);
DISPLAY INVISIBLE (-325 1975);
FORCEPROP 2 LAST SEC_TYPE SH0201
J 0
(-325 2025);
DISPLAY 1.021277 (-325 2025);
PAINT ORANGE (-325 2025);
DISPLAY INVISIBLE (-325 2025);
FORCEADD SC22U16V5MX-4-GP..1
(-250 1150);
FORCEPROP 2 LAST RATED 16V
J 0
(-150 1125);
DISPLAY 0.638298 (-150 1125);
PAINT GREEN (-150 1125);
FORCEPROP 2 LAST TOLERANCE 20%
J 0
(-150 1175);
DISPLAY 0.638298 (-150 1175);
PAINT GREEN (-150 1175);
FORCEPROP 1 LAST LOCATION C22W1
J 0
(-150 1285);
DISPLAY 0.617021 (-150 1285);
PAINT GREEN (-150 1285);
FORCEPROP 2 LASTPIN (-250 1225) $PN 1
R 1
J 0
(-260 1235);
DISPLAY 0.808511 (-260 1235);
PAINT ORANGE (-260 1235);
FORCEPROP 2 LASTPIN (-250 1075) $PN 2
R 1
J 2
(-260 1065);
DISPLAY 0.808511 (-260 1065);
PAINT ORANGE (-260 1065);
FORCEPROP 2 LAST ATTRIBUTE 22UF
J 0
(-150 1225);
DISPLAY 0.638298 (-150 1225);
PAINT GREEN (-150 1225);
FORCEPROP 2 LAST PACK_SIZE 0805
J 0
(-150 1025);
DISPLAY 0.638298 (-150 1025);
PAINT GREEN (-150 1025);
FORCEPROP 2 LAST TYPE X6S
J 0
(-150 1075);
DISPLAY 0.638298 (-150 1075);
PAINT GREEN (-150 1075);
FORCEPROP 1 LAST VALUE SC22U16V5MX-4-GP
R 1
J 0
(-175 945);
DISPLAY 0.617021 (-175 945);
PAINT GREEN (-175 945);
FORCEPROP 1 LAST CDS_LMAN_SYM_OUTLINE -50,25,50,-25
J 0
(-250 1150);
DISPLAY 0.468085 (-250 1150);
PAINT GREEN (-250 1150);
DISPLAY INVISIBLE (-250 1150);
FORCEPROP 2 LAST CDS_LIB w_hdl
J 0
(-250 1150);
PAINT MONO (-250 1150);
DISPLAY INVISIBLE (-250 1150);
FORCEPROP 1 LAST PART_NUMBER 078.22611.0811
J 0
(-250 1150);
DISPLAY 0.617021 (-250 1150);
PAINT GREEN (-250 1150);
DISPLAY INVISIBLE (-250 1150);
FORCEPROP 2 LAST SEC_TYPE SMD-BCG5
J 0
(-225 1225);
DISPLAY 1.021277 (-225 1225);
PAINT ORANGE (-225 1225);
DISPLAY INVISIBLE (-225 1225);
FORCEPROP 2 LAST SEC 1
J 0
(-225 1225);
DISPLAY 0.680851 (-225 1225);
PAINT MONO (-225 1225);
DISPLAY INVISIBLE (-225 1225);
FORCEPROP 1 LAST PACK_TYPE SMD-BCG5
J 0
(-250 1150);
DISPLAY 0.617021 (-250 1150);
PAINT GREEN (-250 1150);
DISPLAY INVISIBLE (-250 1150);
FORCEPROP 1 LAST PATH I246
J 0
(-250 1150);
DISPLAY 0.617021 (-250 1150);
PAINT GREEN (-250 1150);
DISPLAY INVISIBLE (-250 1150);
FORCEADD SC22U16V5MX-4-GP..1
(-950 1150);
FORCEPROP 1 LAST VALUE SC22U16V5MX-4-GP
R 1
J 0
(-875 945);
DISPLAY 0.617021 (-875 945);
PAINT GREEN (-875 945);
FORCEPROP 2 LAST TOLERANCE 20%
J 0
(-850 1175);
DISPLAY 0.638298 (-850 1175);
PAINT GREEN (-850 1175);
FORCEPROP 2 LAST RATED 16V
J 0
(-850 1125);
DISPLAY 0.638298 (-850 1125);
PAINT GREEN (-850 1125);
FORCEPROP 2 LASTPIN (-950 1075) $PN 2
R 1
J 2
(-960 1065);
DISPLAY 0.808511 (-960 1065);
PAINT ORANGE (-960 1065);
FORCEPROP 2 LASTPIN (-950 1225) $PN 1
R 1
J 0
(-960 1235);
DISPLAY 0.808511 (-960 1235);
PAINT ORANGE (-960 1235);
FORCEPROP 2 LAST ATTRIBUTE 22UF
J 0
(-850 1225);
DISPLAY 0.638298 (-850 1225);
PAINT GREEN (-850 1225);
FORCEPROP 2 LAST PACK_SIZE 0805
J 0
(-850 1025);
DISPLAY 0.638298 (-850 1025);
PAINT GREEN (-850 1025);
FORCEPROP 2 LAST TYPE X6S
J 0
(-850 1075);
DISPLAY 0.638298 (-850 1075);
PAINT GREEN (-850 1075);
FORCEPROP 1 LAST LOCATION C22W2
J 0
(-850 1285);
DISPLAY 0.617021 (-850 1285);
PAINT GREEN (-850 1285);
FORCEPROP 1 LAST PACK_TYPE SMD-BCG5
J 0
(-950 1150);
DISPLAY 0.617021 (-950 1150);
PAINT GREEN (-950 1150);
DISPLAY INVISIBLE (-950 1150);
FORCEPROP 2 LAST SEC 1
J 0
(-925 1225);
DISPLAY 0.680851 (-925 1225);
PAINT MONO (-925 1225);
DISPLAY INVISIBLE (-925 1225);
FORCEPROP 2 LAST SEC_TYPE SMD-BCG5
J 0
(-925 1225);
DISPLAY 1.021277 (-925 1225);
PAINT ORANGE (-925 1225);
DISPLAY INVISIBLE (-925 1225);
FORCEPROP 1 LAST PART_NUMBER 078.22611.0811
J 0
(-950 1150);
DISPLAY 0.617021 (-950 1150);
PAINT GREEN (-950 1150);
DISPLAY INVISIBLE (-950 1150);
FORCEPROP 2 LAST CDS_LIB w_hdl
J 0
(-950 1150);
PAINT MONO (-950 1150);
DISPLAY INVISIBLE (-950 1150);
FORCEPROP 1 LAST CDS_LMAN_SYM_OUTLINE -50,25,50,-25
J 0
(-950 1150);
DISPLAY 0.468085 (-950 1150);
PAINT GREEN (-950 1150);
DISPLAY INVISIBLE (-950 1150);
FORCEPROP 1 LAST PATH I247
J 0
(-950 1150);
DISPLAY 0.617021 (-950 1150);
PAINT GREEN (-950 1150);
DISPLAY INVISIBLE (-950 1150);
FORCEADD SC22U16V5MX-4-GP..1
(450 1150);
FORCEPROP 1 LAST VALUE SC22U16V5MX-4-GP
R 1
J 0
(525 945);
DISPLAY 0.617021 (525 945);
PAINT GREEN (525 945);
FORCEPROP 2 LAST RATED 16V
J 0
(575 1125);
DISPLAY 0.638298 (575 1125);
PAINT GREEN (575 1125);
FORCEPROP 2 LASTPIN (450 1225) $PN 1
R 1
J 0
(440 1235);
DISPLAY 0.808511 (440 1235);
PAINT ORANGE (440 1235);
FORCEPROP 2 LAST TOLERANCE 20%
J 0
(575 1175);
DISPLAY 0.638298 (575 1175);
PAINT GREEN (575 1175);
FORCEPROP 2 LASTPIN (450 1075) $PN 2
R 1
J 2
(440 1065);
DISPLAY 0.808511 (440 1065);
PAINT ORANGE (440 1065);
FORCEPROP 2 LAST PACK_SIZE 0805
J 0
(575 1025);
DISPLAY 0.638298 (575 1025);
PAINT GREEN (575 1025);
FORCEPROP 2 LAST TYPE X6S
J 0
(575 1075);
DISPLAY 0.638298 (575 1075);
PAINT GREEN (575 1075);
FORCEPROP 1 LAST LOCATION C22W3
J 0
(575 1285);
DISPLAY 0.617021 (575 1285);
PAINT GREEN (575 1285);
FORCEPROP 2 LAST ATTRIBUTE 22UF
J 0
(575 1225);
DISPLAY 0.638298 (575 1225);
PAINT GREEN (575 1225);
FORCEPROP 1 LAST PATH I249
J 0
(450 1150);
DISPLAY 0.617021 (450 1150);
PAINT GREEN (450 1150);
DISPLAY INVISIBLE (450 1150);
FORCEPROP 1 LAST CDS_LMAN_SYM_OUTLINE -50,25,50,-25
J 0
(450 1150);
DISPLAY 0.468085 (450 1150);
PAINT GREEN (450 1150);
DISPLAY INVISIBLE (450 1150);
FORCEPROP 2 LAST CDS_LIB w_hdl
J 0
(450 1150);
PAINT MONO (450 1150);
DISPLAY INVISIBLE (450 1150);
FORCEPROP 1 LAST PART_NUMBER 078.22611.0811
J 0
(450 1150);
DISPLAY 0.617021 (450 1150);
PAINT GREEN (450 1150);
DISPLAY INVISIBLE (450 1150);
FORCEPROP 2 LAST SEC_TYPE SMD-BCG5
J 0
(475 1225);
DISPLAY 1.021277 (475 1225);
PAINT ORANGE (475 1225);
DISPLAY INVISIBLE (475 1225);
FORCEPROP 2 LAST SEC 1
J 0
(475 1225);
DISPLAY 0.680851 (475 1225);
PAINT MONO (475 1225);
DISPLAY INVISIBLE (475 1225);
FORCEPROP 1 LAST PACK_TYPE SMD-BCG5
J 0
(450 1150);
DISPLAY 0.617021 (450 1150);
PAINT GREEN (450 1150);
DISPLAY INVISIBLE (450 1150);
FORCEADD SC22U16V5MX-4-GP..1
(150 1150);
FORCEPROP 2 LASTPIN (150 1075) $PN 2
R 1
J 2
(140 1065);
DISPLAY 0.808511 (140 1065);
PAINT ORANGE (140 1065);
FORCEPROP 2 LAST RATED 16V
J 0
(250 1125);
DISPLAY 0.638298 (250 1125);
PAINT GREEN (250 1125);
FORCEPROP 2 LAST TYPE X6S
J 0
(250 1075);
DISPLAY 0.638298 (250 1075);
PAINT GREEN (250 1075);
FORCEPROP 2 LAST ATTRIBUTE 22UF
J 0
(250 1225);
DISPLAY 0.638298 (250 1225);
PAINT GREEN (250 1225);
FORCEPROP 2 LAST TOLERANCE 20%
J 0
(250 1175);
DISPLAY 0.638298 (250 1175);
PAINT GREEN (250 1175);
FORCEPROP 1 LAST LOCATION C1G2
J 0
(250 1285);
DISPLAY 0.617021 (250 1285);
PAINT GREEN (250 1285);
FORCEPROP 2 LASTPIN (150 1225) $PN 1
R 1
J 0
(140 1235);
DISPLAY 0.808511 (140 1235);
PAINT ORANGE (140 1235);
FORCEPROP 2 LAST PACK_SIZE 0805
J 0
(250 1025);
DISPLAY 0.638298 (250 1025);
PAINT GREEN (250 1025);
FORCEPROP 1 LAST VALUE SC22U16V5MX-4-GP
R 1
J 0
(225 945);
DISPLAY 0.617021 (225 945);
PAINT GREEN (225 945);
FORCEPROP 1 LAST PATH I250
J 0
(150 1150);
DISPLAY 0.617021 (150 1150);
PAINT GREEN (150 1150);
DISPLAY INVISIBLE (150 1150);
FORCEPROP 1 LAST PACK_TYPE SMD-BCG5
J 0
(150 1150);
DISPLAY 0.617021 (150 1150);
PAINT GREEN (150 1150);
DISPLAY INVISIBLE (150 1150);
FORCEPROP 2 LAST SEC 1
J 0
(175 1225);
DISPLAY 0.680851 (175 1225);
PAINT MONO (175 1225);
DISPLAY INVISIBLE (175 1225);
FORCEPROP 2 LAST SEC_TYPE SMD-BCG5
J 0
(175 1225);
DISPLAY 1.021277 (175 1225);
PAINT ORANGE (175 1225);
DISPLAY INVISIBLE (175 1225);
FORCEPROP 1 LAST PART_NUMBER 078.22611.0811
J 0
(150 1150);
DISPLAY 0.617021 (150 1150);
PAINT GREEN (150 1150);
DISPLAY INVISIBLE (150 1150);
FORCEPROP 2 LAST CDS_LIB w_hdl
J 0
(150 1150);
PAINT MONO (150 1150);
DISPLAY INVISIBLE (150 1150);
FORCEPROP 1 LAST CDS_LMAN_SYM_OUTLINE -50,25,50,-25
J 0
(150 1150);
DISPLAY 0.468085 (150 1150);
PAINT GREEN (150 1150);
DISPLAY INVISIBLE (150 1150);
FORCEADD SC22U16V5MX-4-GP..1
(1150 1150);
FORCEPROP 2 LASTPIN (1150 1075) $PN 2
R 1
J 2
(1140 1065);
DISPLAY 0.808511 (1140 1065);
PAINT ORANGE (1140 1065);
FORCEPROP 2 LAST PACK_SIZE 0805
J 0
(1250 1025);
DISPLAY 0.638298 (1250 1025);
PAINT GREEN (1250 1025);
FORCEPROP 2 LAST TYPE X6S
J 0
(1250 1075);
DISPLAY 0.638298 (1250 1075);
PAINT GREEN (1250 1075);
FORCEPROP 2 LASTPIN (1150 1225) $PN 1
R 1
J 0
(1140 1235);
DISPLAY 0.808511 (1140 1235);
PAINT ORANGE (1140 1235);
FORCEPROP 2 LAST TOLERANCE 20%
J 0
(1250 1175);
DISPLAY 0.638298 (1250 1175);
PAINT GREEN (1250 1175);
FORCEPROP 2 LAST RATED 16V
J 0
(1250 1125);
DISPLAY 0.638298 (1250 1125);
PAINT GREEN (1250 1125);
FORCEPROP 2 LAST ATTRIBUTE 22UF
J 0
(1250 1225);
DISPLAY 0.638298 (1250 1225);
PAINT GREEN (1250 1225);
FORCEPROP 1 LAST LOCATION C22W4
J 0
(1250 1285);
DISPLAY 0.617021 (1250 1285);
PAINT GREEN (1250 1285);
FORCEPROP 1 LAST VALUE SC22U16V5MX-4-GP
R 1
J 0
(1225 945);
DISPLAY 0.617021 (1225 945);
PAINT GREEN (1225 945);
FORCEPROP 1 LAST PACK_TYPE SMD-BCG5
J 0
(1150 1150);
DISPLAY 0.617021 (1150 1150);
PAINT GREEN (1150 1150);
DISPLAY INVISIBLE (1150 1150);
FORCEPROP 2 LAST SEC 1
J 0
(1175 1225);
DISPLAY 0.680851 (1175 1225);
PAINT MONO (1175 1225);
DISPLAY INVISIBLE (1175 1225);
FORCEPROP 2 LAST SEC_TYPE SMD-BCG5
J 0
(1175 1225);
DISPLAY 1.021277 (1175 1225);
PAINT ORANGE (1175 1225);
DISPLAY INVISIBLE (1175 1225);
FORCEPROP 1 LAST PART_NUMBER 078.22611.0811
J 0
(1150 1150);
DISPLAY 0.617021 (1150 1150);
PAINT GREEN (1150 1150);
DISPLAY INVISIBLE (1150 1150);
FORCEPROP 2 LAST CDS_LIB w_hdl
J 0
(1150 1150);
PAINT MONO (1150 1150);
DISPLAY INVISIBLE (1150 1150);
FORCEPROP 1 LAST CDS_LMAN_SYM_OUTLINE -50,25,50,-25
J 0
(1150 1150);
DISPLAY 0.468085 (1150 1150);
PAINT GREEN (1150 1150);
DISPLAY INVISIBLE (1150 1150);
FORCEPROP 1 LAST PATH I251
J 0
(1150 1150);
DISPLAY 0.617021 (1150 1150);
PAINT GREEN (1150 1150);
DISPLAY INVISIBLE (1150 1150);
FORCEADD IND-100NH-35-GP..1
R 1
(-1750 1375);
FORCEPROP 2 LAST PACK_SIZE DCR=0.16MOHM
J 0
(-1900 1100);
DISPLAY 0.638298 (-1900 1100);
PAINT GREEN (-1900 1100);
FORCEPROP 2 LAST RATED ISAT=16A@25C
J 0
(-1900 1200);
DISPLAY 0.638298 (-1900 1200);
PAINT GREEN (-1900 1200);
FORCEPROP 2 LAST ATTRIBUTE 100NH
J 0
(-1900 1250);
DISPLAY 0.638298 (-1900 1250);
PAINT GREEN (-1900 1250);
FORCEPROP 2 LASTPIN (-1600 1350) $PN 2
J 0
(-1590 1360);
DISPLAY 0.808511 (-1590 1360);
PAINT ORANGE (-1590 1360);
FORCEPROP 1 LAST VALUE IND-100NH-35-GP
J 0
(-1900 1300);
DISPLAY 0.617021 (-1900 1300);
PAINT GREEN (-1900 1300);
FORCEPROP 2 LASTPIN (-1900 1350) $PN 1
J 2
(-1910 1360);
DISPLAY 0.808511 (-1910 1360);
PAINT ORANGE (-1910 1360);
FORCEPROP 1 LAST LOCATION L1F1
J 0
(-1875 1425);
DISPLAY 0.617021 (-1875 1425);
PAINT GREEN (-1875 1425);
FORCEPROP 2 LAST TYPE IRMS=29A@DELTA_T<45C
J 0
(-1900 1150);
DISPLAY 0.638298 (-1900 1150);
PAINT GREEN (-1900 1150);
FORCEPROP 1 LAST CDS_LMAN_SYM_OUTLINE -75,100,75,-100
R 1
J 0
(-1750 1375);
DISPLAY 0.468085 (-1750 1375);
PAINT GREEN (-1750 1375);
DISPLAY INVISIBLE (-1750 1375);
FORCEPROP 2 LAST CDS_LIB w_hdl
R 1
J 0
(-1750 1375);
PAINT MONO (-1750 1375);
DISPLAY INVISIBLE (-1750 1375);
FORCEPROP 1 LAST PART_NUMBER 068.1011N.M001
R 1
J 0
(-1750 1375);
DISPLAY 0.617021 (-1750 1375);
PAINT GREEN (-1750 1375);
DISPLAY INVISIBLE (-1750 1375);
FORCEPROP 2 LAST SEC_TYPE DISCRET-G8
J 0
(-1900 1350);
DISPLAY 1.021277 (-1900 1350);
PAINT ORANGE (-1900 1350);
DISPLAY INVISIBLE (-1900 1350);
FORCEPROP 2 LAST SEC 1
J 0
(-1900 1350);
DISPLAY 0.680851 (-1900 1350);
PAINT MONO (-1900 1350);
DISPLAY INVISIBLE (-1900 1350);
FORCEPROP 1 LAST PACK_TYPE DISCRET-G8
R 1
J 0
(-1750 1375);
DISPLAY 0.617021 (-1750 1375);
PAINT GREEN (-1750 1375);
DISPLAY INVISIBLE (-1750 1375);
FORCEPROP 1 LAST PATH I253
R 1
J 0
(-1750 1375);
DISPLAY 0.617021 (-1750 1375);
PAINT GREEN (-1750 1375);
DISPLAY INVISIBLE (-1750 1375);
FORCEADD PVDDQ_GHJ..1
(100 3350);
FORCEPROP 3 LASTPIN (100 3300) SIG_NAME PVDDQ_GHJ\g
J 0
(110 3310);
DISPLAY 0.659574 (110 3310);
PAINT MONO (110 3310);
DISPLAY INVISIBLE (110 3310);
FORCEPROP 1 LAST PATH I257
J 0
(150 3375);
DISPLAY 0.872340 (150 3375);
PAINT AQUA (150 3375);
DISPLAY INVISIBLE (150 3375);
FORCEPROP 2 LAST BOM_COST MEM_VRD_PVPP_AB
J 0
(150 3450);
PAINT MONO (150 3450);
DISPLAY INVISIBLE (150 3450);
FORCEPROP 2 LAST ROOM VDDQ_GHJ_PWR_VR
J 0
(325 3450);
PAINT ORANGE (325 3450);
DISPLAY INVISIBLE (325 3450);
FORCEPROP 2 LAST CDS_LIB mstr_symbols
J 0
(100 3350);
PAINT ORANGE (100 3350);
DISPLAY INVISIBLE (100 3350);
FORCEPROP 1 LAST VOLTAGE 1.2V
J 0
(55 3307);
DISPLAY 0.340426 (55 3307);
PAINT SKYBLUE (55 3307);
DISPLAY INVISIBLE (55 3307);
FORCEPROP 1 LAST BODY_TYPE PLUMBING
J 0
(55 3307);
DISPLAY 0.340426 (55 3307);
PAINT GREEN (55 3307);
DISPLAY INVISIBLE (55 3307);
FORCEPROP 1 LAST HDL_POWER PVDDQ_GHJ
J 1
(100 3400);
DISPLAY 0.872340 (100 3400);
PAINT GREEN (100 3400);
DISPLAY INVISIBLE (100 3400);
FORCEADD GND..1
(100 2575);
FORCEPROP 3 LASTPIN (100 2625) SIG_NAME GND\g
J 0
(110 2635);
DISPLAY 0.659574 (110 2635);
PAINT MONO (110 2635);
DISPLAY INVISIBLE (110 2635);
FORCEPROP 2 LAST ROOM PVCCIN_CPU1_DECAP_VR
J 0
(-450 2650);
PAINT ORANGE (-450 2650);
DISPLAY INVISIBLE (-450 2650);
FORCEPROP 2 LAST CDS_LIB mstr_symbols
J 0
(100 2575);
PAINT ORANGE (100 2575);
DISPLAY INVISIBLE (100 2575);
FORCEPROP 1 LAST SIZE 1B
J 0
(175 2525);
DISPLAY 0.893617 (175 2525);
PAINT GREEN (175 2525);
DISPLAY INVISIBLE (175 2525);
FORCEPROP 1 LAST VOLTAGE 0
J 0
(100 2575);
PAINT SKYBLUE (100 2575);
DISPLAY INVISIBLE (100 2575);
FORCEPROP 1 LAST PATH I258
J 0
(175 2575);
DISPLAY 0.872340 (175 2575);
PAINT AQUA (175 2575);
DISPLAY INVISIBLE (175 2575);
FORCEPROP 1 LAST BODY_TYPE PLUMBING
J 0
(55 2532);
DISPLAY 0.340426 (55 2532);
PAINT GREEN (55 2532);
DISPLAY INVISIBLE (55 2532);
FORCEPROP 1 LAST HDL_POWER GND
J 0
(100 2725);
DISPLAY 0.893617 (100 2725);
PAINT GREEN (100 2725);
DISPLAY INVISIBLE (100 2725);
FORCEADD CAP_A..1
(700 2100);
FORCEPROP 1 LAST PACK_TYPE 0603V
J 0
(750 1900);
DISPLAY 0.617021 (750 1900);
PAINT SKYBLUE (750 1900);
FORCEPROP 1 LAST TOLERANCE 20%
J 0
(750 2050);
DISPLAY 0.617021 (750 2050);
PAINT SKYBLUE (750 2050);
FORCEPROP 1 LAST VOLTAGE 4V
J 0
(750 2100);
DISPLAY 0.617021 (750 2100);
PAINT SKYBLUE (750 2100);
FORCEPROP 1 LAST MATERIAL X6S
J 0
(750 2000);
DISPLAY 0.617021 (750 2000);
PAINT SKYBLUE (750 2000);
FORCEPROP 1 LASTPIN (700 2200) $PN 1
J 0
(710 2180);
DISPLAY 0.617021 (710 2180);
PAINT GREEN (710 2180);
FORCEPROP 1 LAST VALUE 22.0UF
J 0
(750 2150);
DISPLAY 0.617021 (750 2150);
PAINT SKYBLUE (750 2150);
FORCEPROP 1 LAST LOCATION C2D45
J 0
(750 2200);
DISPLAY 0.617021 (750 2200);
PAINT AQUA (750 2200);
FORCEPROP 1 LASTPIN (700 2000) $PN 2
J 0
(710 1980);
DISPLAY 0.617021 (710 1980);
PAINT GREEN (710 1980);
FORCEPROP 1 LAST PART_NUMBER E15431-004
J 0
(750 1950);
DISPLAY 0.617021 (750 1950);
PAINT BLUE (750 1950);
FORCEPROP 0 LAST GROUP PWR_MLCC_CAP
J 0
(756 1862);
DISPLAY 0.638298 (756 1862);
PAINT BROWN (756 1862);
DISPLAY BOTH (756 1862);
FORCEPROP 2 LAST CDS_LOCATION C2D45
J 0
(750 2200);
DISPLAY 0.617021 (750 2200);
PAINT AQUA (750 2200);
DISPLAY INVISIBLE (750 2200);
FORCEPROP 2 LAST BOM_COST PROC
J 0
(700 2100);
PAINT MONO (700 2100);
DISPLAY INVISIBLE (700 2100);
FORCEPROP 2 LAST CDS_LIB dev_discrete
J 0
(700 2100);
PAINT ORANGE (700 2100);
DISPLAY INVISIBLE (700 2100);
FORCEPROP 2 LAST CDS_SEC 1
J 0
(750 2300);
PAINT MONO (750 2300);
DISPLAY INVISIBLE (750 2300);
FORCEPROP 2 LAST $SEC 1
J 0
(750 2300);
PAINT MONO (750 2300);
DISPLAY INVISIBLE (750 2300);
FORCEPROP 2 LAST ROOM PVCCIN_CPU1_DECAP_VR
J 0
(750 2200);
PAINT ORANGE (750 2200);
DISPLAY INVISIBLE (750 2200);
FORCEPROP 1 LAST PATH I261
J 0
(750 2250);
DISPLAY 0.978723 (750 2250);
PAINT WHITE (750 2250);
DISPLAY INVISIBLE (750 2250);
FORCEADD CAP_A..1
(1600 2100);
FORCEPROP 1 LAST TOLERANCE 20%
J 0
(1650 2050);
DISPLAY 0.617021 (1650 2050);
PAINT SKYBLUE (1650 2050);
FORCEPROP 1 LASTPIN (1600 2000) $PN 2
J 0
(1610 1980);
DISPLAY 0.787234 (1610 1980);
PAINT ORANGE (1610 1980);
FORCEPROP 1 LAST VALUE 22.0UF
J 0
(1650 2150);
DISPLAY 0.617021 (1650 2150);
PAINT SKYBLUE (1650 2150);
FORCEPROP 1 LAST LOCATION C3D25
J 0
(1650 2200);
DISPLAY 0.617021 (1650 2200);
PAINT AQUA (1650 2200);
FORCEPROP 1 LAST VOLTAGE 4V
J 0
(1650 2100);
DISPLAY 0.617021 (1650 2100);
PAINT SKYBLUE (1650 2100);
FORCEPROP 1 LAST PACK_TYPE 0603V
J 0
(1650 1900);
DISPLAY 0.617021 (1650 1900);
PAINT SKYBLUE (1650 1900);
FORCEPROP 1 LASTPIN (1600 2200) $PN 1
J 0
(1610 2180);
DISPLAY 0.787234 (1610 2180);
PAINT ORANGE (1610 2180);
FORCEPROP 1 LAST MATERIAL X6S
J 0
(1650 2000);
DISPLAY 0.617021 (1650 2000);
PAINT SKYBLUE (1650 2000);
FORCEPROP 0 LAST GROUP PWR_MLCC_CAP
J 0
(1656 1812);
DISPLAY 0.638298 (1656 1812);
PAINT BROWN (1656 1812);
DISPLAY BOTH (1656 1812);
FORCEPROP 1 LAST PART_NUMBER E15431-004
J 0
(1650 1950);
DISPLAY 0.617021 (1650 1950);
PAINT BLUE (1650 1950);
FORCEPROP 2 LAST ROOM PVCCIN_CPU1_DECAP_VR
J 0
(1675 2200);
PAINT ORANGE (1675 2200);
DISPLAY INVISIBLE (1675 2200);
FORCEPROP 2 LAST CDS_LIB dev_discrete
J 0
(1600 2100);
PAINT ORANGE (1600 2100);
DISPLAY INVISIBLE (1600 2100);
FORCEPROP 2 LAST BOM_COST PROC
J 0
(1600 2100);
PAINT MONO (1600 2100);
DISPLAY INVISIBLE (1600 2100);
FORCEPROP 2 LAST CDS_LOCATION C3D25
J 0
(1650 2200);
DISPLAY 0.617021 (1650 2200);
PAINT AQUA (1650 2200);
DISPLAY INVISIBLE (1650 2200);
FORCEPROP 2 LAST SEC_TYPE 0603V
J 0
(1650 2300);
DISPLAY 1.021277 (1650 2300);
PAINT ORANGE (1650 2300);
DISPLAY INVISIBLE (1650 2300);
FORCEPROP 2 LAST SEC 1
J 0
(1650 2300);
PAINT MONO (1650 2300);
DISPLAY INVISIBLE (1650 2300);
FORCEPROP 1 LAST PATH I262
J 0
(1650 2250);
DISPLAY 0.978723 (1650 2250);
PAINT WHITE (1650 2250);
DISPLAY INVISIBLE (1650 2250);
FORCEADD CAP_A..1
(1300 2100);
FORCEPROP 1 LAST LOCATION C2D47
J 0
(1350 2200);
DISPLAY 0.617021 (1350 2200);
PAINT AQUA (1350 2200);
FORCEPROP 1 LAST TOLERANCE 20%
J 0
(1350 2050);
DISPLAY 0.617021 (1350 2050);
PAINT SKYBLUE (1350 2050);
FORCEPROP 1 LAST PACK_TYPE 0603V
J 0
(1350 1900);
DISPLAY 0.617021 (1350 1900);
PAINT SKYBLUE (1350 1900);
FORCEPROP 1 LAST VALUE 22.0UF
J 0
(1350 2150);
DISPLAY 0.617021 (1350 2150);
PAINT SKYBLUE (1350 2150);
FORCEPROP 1 LASTPIN (1300 2200) $PN 1
J 0
(1310 2180);
DISPLAY 0.787234 (1310 2180);
PAINT ORANGE (1310 2180);
FORCEPROP 1 LAST VOLTAGE 4V
J 0
(1350 2100);
DISPLAY 0.617021 (1350 2100);
PAINT SKYBLUE (1350 2100);
FORCEPROP 1 LASTPIN (1300 2000) $PN 2
J 0
(1310 1980);
DISPLAY 0.787234 (1310 1980);
PAINT ORANGE (1310 1980);
FORCEPROP 1 LAST MATERIAL X6S
J 0
(1350 2000);
DISPLAY 0.617021 (1350 2000);
PAINT SKYBLUE (1350 2000);
FORCEPROP 0 LAST GROUP PWR_MLCC_CAP
J 0
(1356 1862);
DISPLAY 0.638298 (1356 1862);
PAINT BROWN (1356 1862);
DISPLAY BOTH (1356 1862);
FORCEPROP 1 LAST PART_NUMBER E15431-004
J 0
(1350 1950);
DISPLAY 0.617021 (1350 1950);
PAINT BLUE (1350 1950);
FORCEPROP 2 LAST ROOM PVCCIN_CPU1_DECAP_VR
J 0
(1350 2200);
PAINT ORANGE (1350 2200);
DISPLAY INVISIBLE (1350 2200);
FORCEPROP 2 LAST CDS_LIB dev_discrete
J 0
(1300 2100);
PAINT ORANGE (1300 2100);
DISPLAY INVISIBLE (1300 2100);
FORCEPROP 2 LAST BOM_COST PROC
J 0
(1300 2100);
PAINT MONO (1300 2100);
DISPLAY INVISIBLE (1300 2100);
FORCEPROP 2 LAST CDS_LOCATION C2D47
J 0
(1350 2200);
DISPLAY 0.617021 (1350 2200);
PAINT AQUA (1350 2200);
DISPLAY INVISIBLE (1350 2200);
FORCEPROP 2 LAST SEC_TYPE 0603V
J 0
(1350 2300);
DISPLAY 1.021277 (1350 2300);
PAINT ORANGE (1350 2300);
DISPLAY INVISIBLE (1350 2300);
FORCEPROP 2 LAST SEC 1
J 0
(1350 2300);
PAINT MONO (1350 2300);
DISPLAY INVISIBLE (1350 2300);
FORCEPROP 1 LAST PATH I263
J 0
(1350 2250);
DISPLAY 0.978723 (1350 2250);
PAINT WHITE (1350 2250);
DISPLAY INVISIBLE (1350 2250);
FORCEADD CAP_A..1
(1000 2100);
FORCEPROP 0 LAST GROUP PWR_MLCC_CAP
J 0
(1056 1787);
DISPLAY 0.638298 (1056 1787);
PAINT BROWN (1056 1787);
DISPLAY BOTH (1056 1787);
FORCEPROP 1 LAST VALUE 22.0UF
J 0
(1050 2150);
DISPLAY 0.617021 (1050 2150);
PAINT SKYBLUE (1050 2150);
FORCEPROP 1 LAST LOCATION C2D46
J 0
(1050 2200);
DISPLAY 0.617021 (1050 2200);
PAINT AQUA (1050 2200);
FORCEPROP 1 LAST PART_NUMBER E15431-004
J 0
(1050 1950);
DISPLAY 0.617021 (1050 1950);
PAINT BLUE (1050 1950);
FORCEPROP 1 LAST PACK_TYPE 0603V
J 0
(1050 1900);
DISPLAY 0.617021 (1050 1900);
PAINT SKYBLUE (1050 1900);
FORCEPROP 1 LAST MATERIAL X6S
J 0
(1050 2000);
DISPLAY 0.617021 (1050 2000);
PAINT SKYBLUE (1050 2000);
FORCEPROP 1 LAST TOLERANCE 20%
J 0
(1050 2050);
DISPLAY 0.617021 (1050 2050);
PAINT SKYBLUE (1050 2050);
FORCEPROP 1 LASTPIN (1000 2000) $PN 2
J 0
(1010 1980);
DISPLAY 0.787234 (1010 1980);
PAINT ORANGE (1010 1980);
FORCEPROP 1 LAST VOLTAGE 4V
J 0
(1050 2100);
DISPLAY 0.617021 (1050 2100);
PAINT SKYBLUE (1050 2100);
FORCEPROP 1 LASTPIN (1000 2200) $PN 1
J 0
(1010 2180);
DISPLAY 0.787234 (1010 2180);
PAINT ORANGE (1010 2180);
FORCEPROP 2 LAST ROOM PVCCIN_CPU1_DECAP_VR
J 0
(1050 2200);
PAINT ORANGE (1050 2200);
DISPLAY INVISIBLE (1050 2200);
FORCEPROP 2 LAST CDS_LIB dev_discrete
J 0
(1000 2100);
PAINT ORANGE (1000 2100);
DISPLAY INVISIBLE (1000 2100);
FORCEPROP 2 LAST BOM_COST PROC
J 0
(1000 2100);
PAINT MONO (1000 2100);
DISPLAY INVISIBLE (1000 2100);
FORCEPROP 2 LAST CDS_LOCATION C2D46
J 0
(1050 2200);
DISPLAY 0.617021 (1050 2200);
PAINT AQUA (1050 2200);
DISPLAY INVISIBLE (1050 2200);
FORCEPROP 2 LAST SEC_TYPE 0603V
J 0
(1050 2300);
DISPLAY 1.021277 (1050 2300);
PAINT ORANGE (1050 2300);
DISPLAY INVISIBLE (1050 2300);
FORCEPROP 2 LAST SEC 1
J 0
(1050 2300);
PAINT MONO (1050 2300);
DISPLAY INVISIBLE (1050 2300);
FORCEPROP 1 LAST PATH I264
J 0
(1050 2250);
DISPLAY 0.978723 (1050 2250);
PAINT WHITE (1050 2250);
DISPLAY INVISIBLE (1050 2250);
FORCEADD GND..1
(1600 1750);
FORCEPROP 3 LASTPIN (1600 1800) SIG_NAME GND\g
J 0
(1610 1810);
DISPLAY 0.659574 (1610 1810);
PAINT MONO (1610 1810);
DISPLAY INVISIBLE (1610 1810);
FORCEPROP 1 LAST VOLTAGE 0
J 0
(1600 1750);
PAINT SKYBLUE (1600 1750);
DISPLAY INVISIBLE (1600 1750);
FORCEPROP 1 LAST SIZE 1B
J 0
(1675 1700);
DISPLAY 0.893617 (1675 1700);
PAINT GREEN (1675 1700);
DISPLAY INVISIBLE (1675 1700);
FORCEPROP 2 LAST CDS_LIB mstr_symbols
J 0
(1600 1750);
PAINT ORANGE (1600 1750);
DISPLAY INVISIBLE (1600 1750);
FORCEPROP 2 LAST ROOM PVCCIN_CPU1_DECAP_VR
J 0
(1050 1825);
PAINT ORANGE (1050 1825);
DISPLAY INVISIBLE (1050 1825);
FORCEPROP 1 LAST PATH I265
J 0
(1675 1750);
DISPLAY 0.872340 (1675 1750);
PAINT AQUA (1675 1750);
DISPLAY INVISIBLE (1675 1750);
FORCEPROP 1 LAST BODY_TYPE PLUMBING
J 0
(1555 1707);
DISPLAY 0.340426 (1555 1707);
PAINT GREEN (1555 1707);
DISPLAY INVISIBLE (1555 1707);
FORCEPROP 1 LAST HDL_POWER GND
J 0
(1600 1900);
DISPLAY 0.893617 (1600 1900);
PAINT GREEN (1600 1900);
DISPLAY INVISIBLE (1600 1900);
FORCEADD PVDDQ_GHJ..1
(700 2350);
FORCEPROP 3 LASTPIN (700 2300) SIG_NAME PVDDQ_GHJ\g
J 0
(710 2310);
DISPLAY 0.659574 (710 2310);
PAINT MONO (710 2310);
DISPLAY INVISIBLE (710 2310);
FORCEPROP 1 LAST VOLTAGE 1.2V
J 0
(655 2307);
DISPLAY 0.340426 (655 2307);
PAINT SKYBLUE (655 2307);
DISPLAY INVISIBLE (655 2307);
FORCEPROP 2 LAST CDS_LIB mstr_symbols
J 0
(700 2350);
PAINT ORANGE (700 2350);
DISPLAY INVISIBLE (700 2350);
FORCEPROP 2 LAST ROOM VDDQ_GHJ_PWR_VR
J 0
(925 2450);
PAINT ORANGE (925 2450);
DISPLAY INVISIBLE (925 2450);
FORCEPROP 2 LAST BOM_COST MEM_VRD_PVPP_AB
J 0
(750 2450);
PAINT MONO (750 2450);
DISPLAY INVISIBLE (750 2450);
FORCEPROP 1 LAST PATH I266
J 0
(750 2375);
DISPLAY 0.872340 (750 2375);
PAINT AQUA (750 2375);
DISPLAY INVISIBLE (750 2375);
FORCEPROP 1 LAST BODY_TYPE PLUMBING
J 0
(655 2307);
DISPLAY 0.340426 (655 2307);
PAINT GREEN (655 2307);
DISPLAY INVISIBLE (655 2307);
FORCEPROP 1 LAST HDL_POWER PVDDQ_GHJ
J 1
(700 2400);
DISPLAY 0.872340 (700 2400);
PAINT GREEN (700 2400);
DISPLAY INVISIBLE (700 2400);
FORCEADD GND..1
(1625 2850);
FORCEPROP 3 LASTPIN (1625 2900) SIG_NAME GND\g
J 0
(1635 2910);
DISPLAY 0.659574 (1635 2910);
PAINT MONO (1635 2910);
DISPLAY INVISIBLE (1635 2910);
FORCEPROP 1 LAST VOLTAGE 0
J 0
(1625 2850);
PAINT SKYBLUE (1625 2850);
DISPLAY INVISIBLE (1625 2850);
FORCEPROP 1 LAST SIZE 1B
J 0
(1700 2800);
DISPLAY 0.893617 (1700 2800);
PAINT GREEN (1700 2800);
DISPLAY INVISIBLE (1700 2800);
FORCEPROP 2 LAST CDS_LIB mstr_symbols
J 0
(1625 2850);
PAINT ORANGE (1625 2850);
DISPLAY INVISIBLE (1625 2850);
FORCEPROP 2 LAST ROOM PVCCIN_CPU1_DECAP_VR
J 0
(1075 2925);
PAINT ORANGE (1075 2925);
DISPLAY INVISIBLE (1075 2925);
FORCEPROP 1 LAST PATH I267
J 0
(1700 2850);
DISPLAY 0.872340 (1700 2850);
PAINT AQUA (1700 2850);
DISPLAY INVISIBLE (1700 2850);
FORCEPROP 1 LAST BODY_TYPE PLUMBING
J 0
(1580 2807);
DISPLAY 0.340426 (1580 2807);
PAINT GREEN (1580 2807);
DISPLAY INVISIBLE (1580 2807);
FORCEPROP 1 LAST HDL_POWER GND
J 0
(1625 3000);
DISPLAY 0.893617 (1625 3000);
PAINT GREEN (1625 3000);
DISPLAY INVISIBLE (1625 3000);
FORCEADD PVDDQ_GHJ..1
(1625 3275);
FORCEPROP 3 LASTPIN (1625 3225) SIG_NAME PVDDQ_GHJ\g
J 0
(1635 3235);
DISPLAY 0.659574 (1635 3235);
PAINT MONO (1635 3235);
DISPLAY INVISIBLE (1635 3235);
FORCEPROP 1 LAST VOLTAGE 1.2V
J 0
(1580 3232);
DISPLAY 0.340426 (1580 3232);
PAINT SKYBLUE (1580 3232);
DISPLAY INVISIBLE (1580 3232);
FORCEPROP 2 LAST CDS_LIB mstr_symbols
J 0
(1625 3275);
PAINT ORANGE (1625 3275);
DISPLAY INVISIBLE (1625 3275);
FORCEPROP 2 LAST ROOM VDDQ_GHJ_PWR_VR
J 0
(1850 3375);
PAINT ORANGE (1850 3375);
DISPLAY INVISIBLE (1850 3375);
FORCEPROP 2 LAST BOM_COST MEM_VRD_PVPP_AB
J 0
(1675 3375);
PAINT MONO (1675 3375);
DISPLAY INVISIBLE (1675 3375);
FORCEPROP 1 LAST PATH I269
J 0
(1675 3300);
DISPLAY 0.872340 (1675 3300);
PAINT AQUA (1675 3300);
DISPLAY INVISIBLE (1675 3300);
FORCEPROP 1 LAST BODY_TYPE PLUMBING
J 0
(1580 3232);
DISPLAY 0.340426 (1580 3232);
PAINT GREEN (1580 3232);
DISPLAY INVISIBLE (1580 3232);
FORCEPROP 1 LAST HDL_POWER PVDDQ_GHJ
J 1
(1625 3325);
DISPLAY 0.872340 (1625 3325);
PAINT GREEN (1625 3325);
DISPLAY INVISIBLE (1625 3325);
FORCEADD CAP_A..1
(-1450 3100);
FORCEPROP 1 LAST PACK_TYPE 0603V
J 0
(-1400 2900);
DISPLAY 0.617021 (-1400 2900);
PAINT SKYBLUE (-1400 2900);
FORCEPROP 1 LAST VALUE 22.0UF
J 0
(-1400 3150);
DISPLAY 0.617021 (-1400 3150);
PAINT SKYBLUE (-1400 3150);
FORCEPROP 1 LAST VOLTAGE 4V
J 0
(-1400 3100);
DISPLAY 0.617021 (-1400 3100);
PAINT SKYBLUE (-1400 3100);
FORCEPROP 1 LAST TOLERANCE 20%
J 0
(-1400 3050);
DISPLAY 0.617021 (-1400 3050);
PAINT SKYBLUE (-1400 3050);
FORCEPROP 1 LAST LOCATION C2D43
J 0
(-1400 3200);
DISPLAY 0.617021 (-1400 3200);
PAINT AQUA (-1400 3200);
FORCEPROP 1 LAST MATERIAL X6S
J 0
(-1400 3000);
DISPLAY 0.617021 (-1400 3000);
PAINT SKYBLUE (-1400 3000);
FORCEPROP 1 LASTPIN (-1450 3000) $PN 2
J 0
(-1440 2980);
DISPLAY 0.617021 (-1440 2980);
PAINT GREEN (-1440 2980);
FORCEPROP 1 LASTPIN (-1450 3200) $PN 1
J 0
(-1440 3180);
DISPLAY 0.617021 (-1440 3180);
PAINT GREEN (-1440 3180);
FORCEPROP 1 LAST PART_NUMBER E15431-004
J 0
(-1400 2950);
DISPLAY 0.617021 (-1400 2950);
PAINT BLUE (-1400 2950);
FORCEPROP 0 LAST GROUP PWR_MLCC_CAP
J 0
(-1394 2862);
DISPLAY 0.638298 (-1394 2862);
PAINT BROWN (-1394 2862);
DISPLAY BOTH (-1394 2862);
FORCEPROP 2 LAST BOM_COST PROC_SOCKET
J 0
(-1400 3300);
DISPLAY 1.021277 (-1400 3300);
PAINT ORANGE (-1400 3300);
DISPLAY INVISIBLE (-1400 3300);
FORCEPROP 2 LAST CDS_LIB dev_discrete
J 0
(-1450 3100);
PAINT ORANGE (-1450 3100);
DISPLAY INVISIBLE (-1450 3100);
FORCEPROP 2 LAST CDS_SEC 1
J 0
(-1400 3300);
PAINT MONO (-1400 3300);
DISPLAY INVISIBLE (-1400 3300);
FORCEPROP 2 LAST $SEC 1
J 0
(-1400 3300);
PAINT MONO (-1400 3300);
DISPLAY INVISIBLE (-1400 3300);
FORCEPROP 2 LAST ROOM PVCCIN_CPU0_DECAP_VR
J 0
(-1400 3250);
DISPLAY 1.021277 (-1400 3250);
PAINT ORANGE (-1400 3250);
DISPLAY INVISIBLE (-1400 3250);
FORCEPROP 1 LAST PATH I270
J 0
(-1400 3250);
DISPLAY 0.978723 (-1400 3250);
PAINT WHITE (-1400 3250);
DISPLAY INVISIBLE (-1400 3250);
FORCEPROP 2 LAST CDS_LOCATION C2D43
J 0
(-1400 3200);
DISPLAY 0.617021 (-1400 3200);
PAINT AQUA (-1400 3200);
DISPLAY INVISIBLE (-1400 3200);
FORCEADD CAP_A..1
(-1100 3100);
FORCEPROP 1 LAST TOLERANCE 20%
J 0
(-1050 3050);
DISPLAY 0.617021 (-1050 3050);
PAINT SKYBLUE (-1050 3050);
FORCEPROP 1 LAST VOLTAGE 4V
J 0
(-1050 3100);
DISPLAY 0.617021 (-1050 3100);
PAINT SKYBLUE (-1050 3100);
FORCEPROP 1 LAST VALUE 22.0UF
J 0
(-1050 3150);
DISPLAY 0.617021 (-1050 3150);
PAINT SKYBLUE (-1050 3150);
FORCEPROP 1 LAST LOCATION C2D41
J 0
(-1050 3200);
DISPLAY 0.617021 (-1050 3200);
PAINT AQUA (-1050 3200);
FORCEPROP 1 LASTPIN (-1100 3200) $PN 1
J 0
(-1090 3180);
DISPLAY 0.617021 (-1090 3180);
PAINT GREEN (-1090 3180);
FORCEPROP 1 LAST PACK_TYPE 0603V
J 0
(-1050 2900);
DISPLAY 0.617021 (-1050 2900);
PAINT SKYBLUE (-1050 2900);
FORCEPROP 1 LASTPIN (-1100 3000) $PN 2
J 0
(-1090 2980);
DISPLAY 0.617021 (-1090 2980);
PAINT GREEN (-1090 2980);
FORCEPROP 1 LAST MATERIAL X6S
J 0
(-1050 3000);
DISPLAY 0.617021 (-1050 3000);
PAINT SKYBLUE (-1050 3000);
FORCEPROP 0 LAST GROUP PWR_MLCC_CAP
J 0
(-1044 2812);
DISPLAY 0.638298 (-1044 2812);
PAINT BROWN (-1044 2812);
DISPLAY BOTH (-1044 2812);
FORCEPROP 1 LAST PART_NUMBER E15431-004
J 0
(-1050 2950);
DISPLAY 0.617021 (-1050 2950);
PAINT BLUE (-1050 2950);
FORCEPROP 1 LAST PATH I271
J 0
(-1050 3250);
DISPLAY 0.978723 (-1050 3250);
PAINT WHITE (-1050 3250);
DISPLAY INVISIBLE (-1050 3250);
FORCEPROP 2 LAST BOM_COST PROC_SOCKET
J 0
(-1050 3300);
DISPLAY 1.021277 (-1050 3300);
PAINT ORANGE (-1050 3300);
DISPLAY INVISIBLE (-1050 3300);
FORCEPROP 2 LAST CDS_LIB dev_discrete
J 0
(-1100 3100);
PAINT ORANGE (-1100 3100);
DISPLAY INVISIBLE (-1100 3100);
FORCEPROP 2 LAST CDS_SEC 1
J 0
(-1050 3300);
PAINT MONO (-1050 3300);
DISPLAY INVISIBLE (-1050 3300);
FORCEPROP 2 LAST $SEC 1
J 0
(-1050 3300);
PAINT MONO (-1050 3300);
DISPLAY INVISIBLE (-1050 3300);
FORCEPROP 2 LAST ROOM PVCCIN_CPU0_DECAP_VR
J 0
(-1050 3250);
DISPLAY 1.021277 (-1050 3250);
PAINT ORANGE (-1050 3250);
DISPLAY INVISIBLE (-1050 3250);
FORCEPROP 2 LAST CDS_LOCATION C2D41
J 0
(-1050 3200);
DISPLAY 0.617021 (-1050 3200);
PAINT AQUA (-1050 3200);
DISPLAY INVISIBLE (-1050 3200);
FORCEADD CAP_A..1
(-750 3100);
FORCEPROP 1 LAST VOLTAGE 4V
J 0
(-700 3100);
DISPLAY 0.617021 (-700 3100);
PAINT SKYBLUE (-700 3100);
FORCEPROP 1 LASTPIN (-750 3000) $PN 2
J 0
(-740 2980);
DISPLAY 0.617021 (-740 2980);
PAINT GREEN (-740 2980);
FORCEPROP 1 LASTPIN (-750 3200) $PN 1
J 0
(-740 3180);
DISPLAY 0.617021 (-740 3180);
PAINT GREEN (-740 3180);
FORCEPROP 1 LAST LOCATION C2D44
J 0
(-700 3200);
DISPLAY 0.617021 (-700 3200);
PAINT AQUA (-700 3200);
FORCEPROP 1 LAST MATERIAL X6S
J 0
(-700 3000);
DISPLAY 0.617021 (-700 3000);
PAINT SKYBLUE (-700 3000);
FORCEPROP 1 LAST PART_NUMBER E15431-004
J 0
(-700 2950);
DISPLAY 0.617021 (-700 2950);
PAINT BLUE (-700 2950);
FORCEPROP 1 LAST PACK_TYPE 0603V
J 0
(-700 2900);
DISPLAY 0.617021 (-700 2900);
PAINT SKYBLUE (-700 2900);
FORCEPROP 0 LAST GROUP PWR_MLCC_CAP
J 0
(-694 2862);
DISPLAY 0.638298 (-694 2862);
PAINT BROWN (-694 2862);
DISPLAY BOTH (-694 2862);
FORCEPROP 1 LAST TOLERANCE 20%
J 0
(-700 3050);
DISPLAY 0.617021 (-700 3050);
PAINT SKYBLUE (-700 3050);
FORCEPROP 1 LAST VALUE 22.0UF
J 0
(-700 3150);
DISPLAY 0.617021 (-700 3150);
PAINT SKYBLUE (-700 3150);
FORCEPROP 1 LAST PATH I272
J 0
(-700 3250);
DISPLAY 0.978723 (-700 3250);
PAINT WHITE (-700 3250);
DISPLAY INVISIBLE (-700 3250);
FORCEPROP 2 LAST BOM_COST PROC_SOCKET
J 0
(-700 3300);
DISPLAY 1.021277 (-700 3300);
PAINT ORANGE (-700 3300);
DISPLAY INVISIBLE (-700 3300);
FORCEPROP 2 LAST CDS_LIB dev_discrete
J 0
(-750 3100);
PAINT ORANGE (-750 3100);
DISPLAY INVISIBLE (-750 3100);
FORCEPROP 2 LAST CDS_SEC 1
J 0
(-700 3300);
PAINT MONO (-700 3300);
DISPLAY INVISIBLE (-700 3300);
FORCEPROP 2 LAST $SEC 1
J 0
(-700 3300);
PAINT MONO (-700 3300);
DISPLAY INVISIBLE (-700 3300);
FORCEPROP 2 LAST ROOM PVCCIN_CPU0_DECAP_VR
J 0
(-700 3250);
DISPLAY 1.021277 (-700 3250);
PAINT ORANGE (-700 3250);
DISPLAY INVISIBLE (-700 3250);
FORCEPROP 2 LAST CDS_LOCATION C2D44
J 0
(-700 3200);
DISPLAY 0.617021 (-700 3200);
PAINT AQUA (-700 3200);
DISPLAY INVISIBLE (-700 3200);
FORCEADD CAP_A..1
(-350 3100);
FORCEPROP 1 LAST PACK_TYPE 0603V
J 0
(-300 2900);
DISPLAY 0.617021 (-300 2900);
PAINT SKYBLUE (-300 2900);
FORCEPROP 0 LAST GROUP PWR_MLCC_CAP
J 0
(-319 2812);
DISPLAY 0.638298 (-319 2812);
PAINT BROWN (-319 2812);
DISPLAY BOTH (-319 2812);
FORCEPROP 1 LAST LOCATION C2D42
J 0
(-300 3200);
DISPLAY 0.617021 (-300 3200);
PAINT AQUA (-300 3200);
FORCEPROP 1 LAST MATERIAL X6S
J 0
(-300 3000);
DISPLAY 0.617021 (-300 3000);
PAINT SKYBLUE (-300 3000);
FORCEPROP 1 LASTPIN (-350 3000) $PN 2
J 0
(-340 2980);
DISPLAY 0.617021 (-340 2980);
PAINT GREEN (-340 2980);
FORCEPROP 1 LASTPIN (-350 3200) $PN 1
J 0
(-340 3180);
DISPLAY 0.617021 (-340 3180);
PAINT GREEN (-340 3180);
FORCEPROP 1 LAST VALUE 22.0UF
J 0
(-300 3150);
DISPLAY 0.617021 (-300 3150);
PAINT SKYBLUE (-300 3150);
FORCEPROP 1 LAST PART_NUMBER E15431-004
J 0
(-300 2950);
DISPLAY 0.617021 (-300 2950);
PAINT BLUE (-300 2950);
FORCEPROP 1 LAST VOLTAGE 4V
J 0
(-300 3100);
DISPLAY 0.617021 (-300 3100);
PAINT SKYBLUE (-300 3100);
FORCEPROP 1 LAST TOLERANCE 20%
J 0
(-300 3050);
DISPLAY 0.617021 (-300 3050);
PAINT SKYBLUE (-300 3050);
FORCEPROP 1 LAST PATH I273
J 0
(-300 3250);
DISPLAY 0.978723 (-300 3250);
PAINT WHITE (-300 3250);
DISPLAY INVISIBLE (-300 3250);
FORCEPROP 2 LAST BOM_COST PROC_SOCKET
J 0
(-300 3300);
DISPLAY 1.021277 (-300 3300);
PAINT ORANGE (-300 3300);
DISPLAY INVISIBLE (-300 3300);
FORCEPROP 2 LAST CDS_LIB dev_discrete
J 0
(-350 3100);
PAINT ORANGE (-350 3100);
DISPLAY INVISIBLE (-350 3100);
FORCEPROP 2 LAST CDS_SEC 1
J 0
(-300 3300);
PAINT MONO (-300 3300);
DISPLAY INVISIBLE (-300 3300);
FORCEPROP 2 LAST $SEC 1
J 0
(-300 3300);
PAINT MONO (-300 3300);
DISPLAY INVISIBLE (-300 3300);
FORCEPROP 2 LAST ROOM PVCCIN_CPU0_DECAP_VR
J 0
(-300 3250);
DISPLAY 1.021277 (-300 3250);
PAINT ORANGE (-300 3250);
DISPLAY INVISIBLE (-300 3250);
FORCEPROP 2 LAST CDS_LOCATION C2D42
J 0
(-300 3200);
DISPLAY 0.617021 (-300 3200);
PAINT AQUA (-300 3200);
DISPLAY INVISIBLE (-300 3200);
FORCEADD CAP_A..1
(-2275 250);
FORCEPROP 1 LAST LOCATION C2G10
J 0
(-2225 350);
DISPLAY 0.617021 (-2225 350);
PAINT AQUA (-2225 350);
FORCEPROP 1 LAST TOLERANCE 20%
J 0
(-2225 200);
DISPLAY 0.617021 (-2225 200);
PAINT SKYBLUE (-2225 200);
FORCEPROP 1 LAST MATERIAL X5R
J 0
(-2225 150);
DISPLAY 0.617021 (-2225 150);
PAINT SKYBLUE (-2225 150);
FORCEPROP 1 LASTPIN (-2275 150) $PN 2
J 0
(-2265 130);
DISPLAY 0.617021 (-2265 130);
PAINT ORANGE (-2265 130);
FORCEPROP 1 LASTPIN (-2275 350) $PN 1
J 0
(-2265 330);
DISPLAY 0.617021 (-2265 330);
PAINT ORANGE (-2265 330);
FORCEPROP 1 LAST VALUE 47UF
J 0
(-2225 300);
DISPLAY 0.617021 (-2225 300);
PAINT SKYBLUE (-2225 300);
FORCEPROP 1 LAST VOLTAGE 4V
J 0
(-2225 250);
DISPLAY 0.617021 (-2225 250);
PAINT SKYBLUE (-2225 250);
FORCEPROP 1 LAST PACK_TYPE 0603V
J 0
(-2225 50);
DISPLAY 0.617021 (-2225 50);
PAINT SKYBLUE (-2225 50);
FORCEPROP 1 LAST PART_NUMBER 602433-106
J 0
(-2225 100);
DISPLAY 0.617021 (-2225 100);
PAINT BLUE (-2225 100);
FORCEPROP 0 LAST GROUP PWR_MLCC_CAP
J 0
(-2244 -113);
DISPLAY 0.638298 (-2244 -113);
PAINT BROWN (-2244 -113);
DISPLAY BOTH (-2244 -113);
FORCEPROP 0 LAST BOM_SS E15431-004
J 0
(-2248 -14);
DISPLAY 0.510638 (-2248 -14);
PAINT BROWN (-2248 -14);
DISPLAY BOTH (-2248 -14);
FORCEPROP 1 LAST PATH I274
J 0
(-2225 400);
DISPLAY 0.978723 (-2225 400);
PAINT WHITE (-2225 400);
DISPLAY INVISIBLE (-2225 400);
FORCEPROP 2 LAST CDS_LIB dev_discrete
J 0
(-2275 250);
PAINT ORANGE (-2275 250);
DISPLAY INVISIBLE (-2275 250);
FORCEPROP 2 LAST SEC 1
J 0
(-2225 450);
DISPLAY 0.680851 (-2225 450);
PAINT MONO (-2225 450);
DISPLAY INVISIBLE (-2225 450);
FORCEPROP 2 LAST SEC_TYPE 0603V
J 0
(-2225 450);
DISPLAY 1.021277 (-2225 450);
PAINT ORANGE (-2225 450);
DISPLAY INVISIBLE (-2225 450);
FORCEPROP 2 LAST CDS_SEC 1
J 0
(-2225 400);
PAINT ORANGE (-2225 400);
DISPLAY INVISIBLE (-2225 400);
FORCEPROP 2 LAST CDS_LOCATION C2G10
J 0
(-2225 350);
DISPLAY 0.617021 (-2225 350);
PAINT AQUA (-2225 350);
DISPLAY INVISIBLE (-2225 350);
FORCEADD CAP_A..1
(-1975 250);
FORCEPROP 1 LASTPIN (-1975 350) $PN 1
J 0
(-1965 330);
DISPLAY 0.617021 (-1965 330);
PAINT ORANGE (-1965 330);
FORCEPROP 1 LASTPIN (-1975 150) $PN 2
J 0
(-1965 130);
DISPLAY 0.617021 (-1965 130);
PAINT ORANGE (-1965 130);
FORCEPROP 0 LAST GROUP PWR_MLCC_CAP
J 0
(-1944 -163);
DISPLAY 0.638298 (-1944 -163);
PAINT BROWN (-1944 -163);
DISPLAY BOTH (-1944 -163);
FORCEPROP 1 LAST PACK_TYPE 0603V
J 0
(-1925 50);
DISPLAY 0.617021 (-1925 50);
PAINT SKYBLUE (-1925 50);
FORCEPROP 1 LAST PART_NUMBER 602433-106
J 0
(-1925 100);
DISPLAY 0.617021 (-1925 100);
PAINT BLUE (-1925 100);
FORCEPROP 1 LAST MATERIAL X5R
J 0
(-1925 150);
DISPLAY 0.617021 (-1925 150);
PAINT SKYBLUE (-1925 150);
FORCEPROP 1 LAST TOLERANCE 20%
J 0
(-1925 200);
DISPLAY 0.617021 (-1925 200);
PAINT SKYBLUE (-1925 200);
FORCEPROP 1 LAST VOLTAGE 4V
J 0
(-1925 250);
DISPLAY 0.617021 (-1925 250);
PAINT SKYBLUE (-1925 250);
FORCEPROP 1 LAST VALUE 47UF
J 0
(-1925 300);
DISPLAY 0.617021 (-1925 300);
PAINT SKYBLUE (-1925 300);
FORCEPROP 1 LAST LOCATION C2G11
J 0
(-1925 350);
DISPLAY 0.617021 (-1925 350);
PAINT AQUA (-1925 350);
FORCEPROP 0 LAST BOM_SS E15431-004
J 0
(-1966 -58);
DISPLAY 0.510638 (-1966 -58);
PAINT BROWN (-1966 -58);
DISPLAY BOTH (-1966 -58);
FORCEPROP 1 LAST PATH I275
J 0
(-1925 400);
DISPLAY 0.978723 (-1925 400);
PAINT WHITE (-1925 400);
DISPLAY INVISIBLE (-1925 400);
FORCEPROP 2 LAST CDS_SEC 1
J 0
(-1925 400);
PAINT ORANGE (-1925 400);
DISPLAY INVISIBLE (-1925 400);
FORCEPROP 2 LAST SEC_TYPE 0603V
J 0
(-1925 450);
DISPLAY 1.021277 (-1925 450);
PAINT ORANGE (-1925 450);
DISPLAY INVISIBLE (-1925 450);
FORCEPROP 2 LAST SEC 1
J 0
(-1925 450);
DISPLAY 0.680851 (-1925 450);
PAINT MONO (-1925 450);
DISPLAY INVISIBLE (-1925 450);
FORCEPROP 2 LAST CDS_LIB dev_discrete
J 0
(-1975 250);
PAINT ORANGE (-1975 250);
DISPLAY INVISIBLE (-1975 250);
FORCEPROP 2 LAST CDS_LOCATION C2G11
J 0
(-1925 350);
DISPLAY 0.617021 (-1925 350);
PAINT AQUA (-1925 350);
DISPLAY INVISIBLE (-1925 350);
FORCEADD CAP_A..1
(-1675 250);
FORCEPROP 1 LAST PACK_TYPE 0603V
J 0
(-1625 50);
DISPLAY 0.617021 (-1625 50);
PAINT SKYBLUE (-1625 50);
FORCEPROP 1 LAST LOCATION C2G12
J 0
(-1625 350);
DISPLAY 0.617021 (-1625 350);
PAINT AQUA (-1625 350);
FORCEPROP 1 LAST TOLERANCE 20%
J 0
(-1625 200);
DISPLAY 0.617021 (-1625 200);
PAINT SKYBLUE (-1625 200);
FORCEPROP 1 LAST MATERIAL X5R
J 0
(-1625 150);
DISPLAY 0.617021 (-1625 150);
PAINT SKYBLUE (-1625 150);
FORCEPROP 1 LASTPIN (-1675 150) $PN 2
J 0
(-1665 130);
DISPLAY 0.617021 (-1665 130);
PAINT ORANGE (-1665 130);
FORCEPROP 1 LASTPIN (-1675 350) $PN 1
J 0
(-1665 330);
DISPLAY 0.617021 (-1665 330);
PAINT ORANGE (-1665 330);
FORCEPROP 1 LAST VALUE 47UF
J 0
(-1625 300);
DISPLAY 0.617021 (-1625 300);
PAINT SKYBLUE (-1625 300);
FORCEPROP 1 LAST VOLTAGE 4V
J 0
(-1625 250);
DISPLAY 0.617021 (-1625 250);
PAINT SKYBLUE (-1625 250);
FORCEPROP 1 LAST PART_NUMBER 602433-106
J 0
(-1625 100);
DISPLAY 0.617021 (-1625 100);
PAINT BLUE (-1625 100);
FORCEPROP 0 LAST GROUP PWR_MLCC_CAP
J 0
(-1619 -113);
DISPLAY 0.638298 (-1619 -113);
PAINT BROWN (-1619 -113);
DISPLAY BOTH (-1619 -113);
FORCEPROP 0 LAST BOM_SS E15431-004
J 0
(-1668 -36);
DISPLAY 0.510638 (-1668 -36);
PAINT BROWN (-1668 -36);
DISPLAY BOTH (-1668 -36);
FORCEPROP 1 LAST PATH I276
J 0
(-1625 400);
DISPLAY 0.978723 (-1625 400);
PAINT WHITE (-1625 400);
DISPLAY INVISIBLE (-1625 400);
FORCEPROP 2 LAST CDS_LIB dev_discrete
J 0
(-1675 250);
PAINT ORANGE (-1675 250);
DISPLAY INVISIBLE (-1675 250);
FORCEPROP 2 LAST SEC 1
J 0
(-1625 450);
DISPLAY 0.680851 (-1625 450);
PAINT MONO (-1625 450);
DISPLAY INVISIBLE (-1625 450);
FORCEPROP 2 LAST SEC_TYPE 0603V
J 0
(-1625 450);
DISPLAY 1.021277 (-1625 450);
PAINT ORANGE (-1625 450);
DISPLAY INVISIBLE (-1625 450);
FORCEPROP 2 LAST CDS_SEC 1
J 0
(-1625 400);
PAINT ORANGE (-1625 400);
DISPLAY INVISIBLE (-1625 400);
FORCEPROP 2 LAST CDS_LOCATION C2G12
J 0
(-1625 350);
DISPLAY 0.617021 (-1625 350);
PAINT AQUA (-1625 350);
DISPLAY INVISIBLE (-1625 350);
FORCEADD CAP_A..1
(-1400 250);
FORCEPROP 1 LAST VOLTAGE 4V
J 0
(-1350 250);
DISPLAY 0.617021 (-1350 250);
PAINT SKYBLUE (-1350 250);
FORCEPROP 0 LAST GROUP PWR_MLCC_CAP
J 0
(-1344 -163);
DISPLAY 0.638298 (-1344 -163);
PAINT BROWN (-1344 -163);
DISPLAY BOTH (-1344 -163);
FORCEPROP 1 LAST PACK_TYPE 0603V
J 0
(-1350 50);
DISPLAY 0.617021 (-1350 50);
PAINT SKYBLUE (-1350 50);
FORCEPROP 1 LASTPIN (-1400 350) $PN 1
J 0
(-1390 330);
DISPLAY 0.617021 (-1390 330);
PAINT ORANGE (-1390 330);
FORCEPROP 1 LASTPIN (-1400 150) $PN 2
J 0
(-1390 130);
DISPLAY 0.617021 (-1390 130);
PAINT ORANGE (-1390 130);
FORCEPROP 1 LAST PART_NUMBER 602433-106
J 0
(-1350 100);
DISPLAY 0.617021 (-1350 100);
PAINT BLUE (-1350 100);
FORCEPROP 1 LAST MATERIAL X5R
J 0
(-1350 150);
DISPLAY 0.617021 (-1350 150);
PAINT SKYBLUE (-1350 150);
FORCEPROP 1 LAST LOCATION C2G1
J 0
(-1350 350);
DISPLAY 0.617021 (-1350 350);
PAINT AQUA (-1350 350);
FORCEPROP 1 LAST VALUE 47UF
J 0
(-1350 300);
DISPLAY 0.617021 (-1350 300);
PAINT SKYBLUE (-1350 300);
FORCEPROP 1 LAST TOLERANCE 20%
J 0
(-1350 200);
DISPLAY 0.617021 (-1350 200);
PAINT SKYBLUE (-1350 200);
FORCEPROP 0 LAST BOM_SS E15431-004
J 0
(-1405 -80);
DISPLAY 0.510638 (-1405 -80);
PAINT BROWN (-1405 -80);
DISPLAY BOTH (-1405 -80);
FORCEPROP 1 LAST PATH I277
J 0
(-1350 400);
DISPLAY 0.978723 (-1350 400);
PAINT WHITE (-1350 400);
DISPLAY INVISIBLE (-1350 400);
FORCEPROP 2 LAST CDS_SEC 1
J 0
(-1350 400);
PAINT ORANGE (-1350 400);
DISPLAY INVISIBLE (-1350 400);
FORCEPROP 2 LAST SEC_TYPE 0603V
J 0
(-1350 450);
DISPLAY 1.021277 (-1350 450);
PAINT ORANGE (-1350 450);
DISPLAY INVISIBLE (-1350 450);
FORCEPROP 2 LAST SEC 1
J 0
(-1350 450);
DISPLAY 0.680851 (-1350 450);
PAINT MONO (-1350 450);
DISPLAY INVISIBLE (-1350 450);
FORCEPROP 2 LAST CDS_LIB dev_discrete
J 0
(-1400 250);
PAINT ORANGE (-1400 250);
DISPLAY INVISIBLE (-1400 250);
FORCEPROP 2 LAST CDS_LOCATION C2G1
J 0
(-1350 350);
DISPLAY 0.617021 (-1350 350);
PAINT AQUA (-1350 350);
DISPLAY INVISIBLE (-1350 350);
FORCEADD CAP_A..1
(-1125 250);
FORCEPROP 0 LAST GROUP PWR_MLCC_CAP
J 0
(-1044 -113);
DISPLAY 0.638298 (-1044 -113);
PAINT BROWN (-1044 -113);
DISPLAY BOTH (-1044 -113);
FORCEPROP 1 LAST VOLTAGE 4V
J 0
(-1075 250);
DISPLAY 0.617021 (-1075 250);
PAINT SKYBLUE (-1075 250);
FORCEPROP 1 LASTPIN (-1125 150) $PN 2
J 0
(-1115 130);
DISPLAY 0.617021 (-1115 130);
PAINT ORANGE (-1115 130);
FORCEPROP 1 LAST MATERIAL X5R
J 0
(-1075 150);
DISPLAY 0.617021 (-1075 150);
PAINT SKYBLUE (-1075 150);
FORCEPROP 1 LAST TOLERANCE 20%
J 0
(-1075 200);
DISPLAY 0.617021 (-1075 200);
PAINT SKYBLUE (-1075 200);
FORCEPROP 1 LAST PACK_TYPE 0603V
J 0
(-1075 50);
DISPLAY 0.617021 (-1075 50);
PAINT SKYBLUE (-1075 50);
FORCEPROP 1 LAST PART_NUMBER 602433-106
J 0
(-1075 100);
DISPLAY 0.617021 (-1075 100);
PAINT BLUE (-1075 100);
FORCEPROP 1 LASTPIN (-1125 350) $PN 1
J 0
(-1115 330);
DISPLAY 0.617021 (-1115 330);
PAINT ORANGE (-1115 330);
FORCEPROP 1 LAST VALUE 47UF
J 0
(-1075 300);
DISPLAY 0.617021 (-1075 300);
PAINT SKYBLUE (-1075 300);
FORCEPROP 1 LAST LOCATION C2G9
J 0
(-1075 350);
DISPLAY 0.617021 (-1075 350);
PAINT AQUA (-1075 350);
FORCEPROP 0 LAST BOM_SS E15431-004
J 0
(-1126 -20);
DISPLAY 0.510638 (-1126 -20);
PAINT BROWN (-1126 -20);
DISPLAY BOTH (-1126 -20);
FORCEPROP 2 LAST CDS_SEC 1
J 0
(-1075 400);
PAINT ORANGE (-1075 400);
DISPLAY INVISIBLE (-1075 400);
FORCEPROP 2 LAST SEC_TYPE 0603V
J 0
(-1075 450);
DISPLAY 1.021277 (-1075 450);
PAINT ORANGE (-1075 450);
DISPLAY INVISIBLE (-1075 450);
FORCEPROP 2 LAST SEC 1
J 0
(-1075 450);
DISPLAY 0.680851 (-1075 450);
PAINT MONO (-1075 450);
DISPLAY INVISIBLE (-1075 450);
FORCEPROP 2 LAST CDS_LIB dev_discrete
J 0
(-1125 250);
PAINT ORANGE (-1125 250);
DISPLAY INVISIBLE (-1125 250);
FORCEPROP 1 LAST PATH I278
J 0
(-1075 400);
DISPLAY 0.978723 (-1075 400);
PAINT WHITE (-1075 400);
DISPLAY INVISIBLE (-1075 400);
FORCEPROP 2 LAST CDS_LOCATION C2G9
J 0
(-1075 350);
DISPLAY 0.617021 (-1075 350);
PAINT AQUA (-1075 350);
DISPLAY INVISIBLE (-1075 350);
FORCEADD CAP_A..1
(-825 250);
FORCEPROP 0 LAST GROUP PWR_MLCC_CAP
J 0
(-769 -163);
DISPLAY 0.638298 (-769 -163);
PAINT BROWN (-769 -163);
DISPLAY BOTH (-769 -163);
FORCEPROP 1 LAST VOLTAGE 4V
J 0
(-775 250);
DISPLAY 0.617021 (-775 250);
PAINT SKYBLUE (-775 250);
FORCEPROP 1 LASTPIN (-825 350) $PN 1
J 0
(-815 330);
DISPLAY 0.617021 (-815 330);
PAINT ORANGE (-815 330);
FORCEPROP 1 LASTPIN (-825 150) $PN 2
J 0
(-815 130);
DISPLAY 0.617021 (-815 130);
PAINT ORANGE (-815 130);
FORCEPROP 1 LAST LOCATION C2G2
J 0
(-775 350);
DISPLAY 0.617021 (-775 350);
PAINT AQUA (-775 350);
FORCEPROP 1 LAST PACK_TYPE 0603V
J 0
(-775 50);
DISPLAY 0.617021 (-775 50);
PAINT SKYBLUE (-775 50);
FORCEPROP 1 LAST PART_NUMBER 602433-106
J 0
(-775 100);
DISPLAY 0.617021 (-775 100);
PAINT BLUE (-775 100);
FORCEPROP 1 LAST MATERIAL X5R
J 0
(-775 150);
DISPLAY 0.617021 (-775 150);
PAINT SKYBLUE (-775 150);
FORCEPROP 1 LAST TOLERANCE 20%
J 0
(-775 200);
DISPLAY 0.617021 (-775 200);
PAINT SKYBLUE (-775 200);
FORCEPROP 1 LAST VALUE 47UF
J 0
(-775 300);
DISPLAY 0.617021 (-775 300);
PAINT SKYBLUE (-775 300);
FORCEPROP 0 LAST BOM_SS E15431-004
J 0
(-826 -60);
DISPLAY 0.510638 (-826 -60);
PAINT BROWN (-826 -60);
DISPLAY BOTH (-826 -60);
FORCEPROP 2 LAST CDS_SEC 1
J 0
(-775 400);
PAINT ORANGE (-775 400);
DISPLAY INVISIBLE (-775 400);
FORCEPROP 2 LAST SEC_TYPE 0603V
J 0
(-775 450);
DISPLAY 1.021277 (-775 450);
PAINT ORANGE (-775 450);
DISPLAY INVISIBLE (-775 450);
FORCEPROP 2 LAST SEC 1
J 0
(-775 450);
DISPLAY 0.680851 (-775 450);
PAINT MONO (-775 450);
DISPLAY INVISIBLE (-775 450);
FORCEPROP 2 LAST CDS_LIB dev_discrete
J 0
(-825 250);
PAINT ORANGE (-825 250);
DISPLAY INVISIBLE (-825 250);
FORCEPROP 1 LAST PATH I279
J 0
(-775 400);
DISPLAY 0.978723 (-775 400);
PAINT WHITE (-775 400);
DISPLAY INVISIBLE (-775 400);
FORCEPROP 2 LAST CDS_LOCATION C2G2
J 0
(-775 350);
DISPLAY 0.617021 (-775 350);
PAINT AQUA (-775 350);
DISPLAY INVISIBLE (-775 350);
FORCEADD CAP_A..1
(-525 250);
FORCEPROP 0 LAST GROUP PWR_MLCC_CAP
J 0
(-469 -113);
DISPLAY 0.638298 (-469 -113);
PAINT BROWN (-469 -113);
DISPLAY BOTH (-469 -113);
FORCEPROP 1 LAST VOLTAGE 4V
J 0
(-475 250);
DISPLAY 0.617021 (-475 250);
PAINT SKYBLUE (-475 250);
FORCEPROP 1 LAST VALUE 47UF
J 0
(-475 300);
DISPLAY 0.617021 (-475 300);
PAINT SKYBLUE (-475 300);
FORCEPROP 1 LASTPIN (-525 350) $PN 1
J 0
(-515 330);
DISPLAY 0.617021 (-515 330);
PAINT ORANGE (-515 330);
FORCEPROP 1 LASTPIN (-525 150) $PN 2
J 0
(-515 130);
DISPLAY 0.617021 (-515 130);
PAINT ORANGE (-515 130);
FORCEPROP 1 LAST TOLERANCE 20%
J 0
(-475 200);
DISPLAY 0.617021 (-475 200);
PAINT SKYBLUE (-475 200);
FORCEPROP 1 LAST LOCATION C2G3
J 0
(-475 350);
DISPLAY 0.617021 (-475 350);
PAINT AQUA (-475 350);
FORCEPROP 1 LAST MATERIAL X5R
J 0
(-475 150);
DISPLAY 0.617021 (-475 150);
PAINT SKYBLUE (-475 150);
FORCEPROP 1 LAST PACK_TYPE 0603V
J 0
(-475 50);
DISPLAY 0.617021 (-475 50);
PAINT SKYBLUE (-475 50);
FORCEPROP 1 LAST PART_NUMBER 602433-106
J 0
(-475 100);
DISPLAY 0.617021 (-475 100);
PAINT BLUE (-475 100);
FORCEPROP 0 LAST BOM_SS E15431-004
J 0
(-526 -30);
DISPLAY 0.510638 (-526 -30);
PAINT BROWN (-526 -30);
DISPLAY BOTH (-526 -30);
FORCEPROP 2 LAST CDS_SEC 1
J 0
(-475 400);
PAINT ORANGE (-475 400);
DISPLAY INVISIBLE (-475 400);
FORCEPROP 2 LAST SEC_TYPE 0603V
J 0
(-475 450);
DISPLAY 1.021277 (-475 450);
PAINT ORANGE (-475 450);
DISPLAY INVISIBLE (-475 450);
FORCEPROP 2 LAST SEC 1
J 0
(-475 450);
DISPLAY 0.680851 (-475 450);
PAINT MONO (-475 450);
DISPLAY INVISIBLE (-475 450);
FORCEPROP 2 LAST CDS_LIB dev_discrete
J 0
(-525 250);
PAINT ORANGE (-525 250);
DISPLAY INVISIBLE (-525 250);
FORCEPROP 1 LAST PATH I280
J 0
(-475 400);
DISPLAY 0.978723 (-475 400);
PAINT WHITE (-475 400);
DISPLAY INVISIBLE (-475 400);
FORCEPROP 2 LAST CDS_LOCATION C2G3
J 0
(-475 350);
DISPLAY 0.617021 (-475 350);
PAINT AQUA (-475 350);
DISPLAY INVISIBLE (-475 350);
FORCEADD CAP_A..1
(-250 250);
FORCEPROP 0 LAST GROUP PWR_MLCC_CAP
J 0
(-194 -163);
DISPLAY 0.638298 (-194 -163);
PAINT BROWN (-194 -163);
DISPLAY BOTH (-194 -163);
FORCEPROP 1 LAST VOLTAGE 4V
J 0
(-200 250);
DISPLAY 0.617021 (-200 250);
PAINT SKYBLUE (-200 250);
FORCEPROP 1 LAST VALUE 47UF
J 0
(-200 300);
DISPLAY 0.617021 (-200 300);
PAINT SKYBLUE (-200 300);
FORCEPROP 1 LASTPIN (-250 350) $PN 1
J 0
(-240 330);
DISPLAY 0.617021 (-240 330);
PAINT ORANGE (-240 330);
FORCEPROP 1 LAST MATERIAL X5R
J 0
(-200 150);
DISPLAY 0.617021 (-200 150);
PAINT SKYBLUE (-200 150);
FORCEPROP 1 LAST TOLERANCE 20%
J 0
(-200 200);
DISPLAY 0.617021 (-200 200);
PAINT SKYBLUE (-200 200);
FORCEPROP 1 LAST LOCATION C2G4
J 0
(-200 350);
DISPLAY 0.617021 (-200 350);
PAINT AQUA (-200 350);
FORCEPROP 1 LASTPIN (-250 150) $PN 2
J 0
(-240 130);
DISPLAY 0.617021 (-240 130);
PAINT ORANGE (-240 130);
FORCEPROP 1 LAST PACK_TYPE 0603V
J 0
(-200 50);
DISPLAY 0.617021 (-200 50);
PAINT SKYBLUE (-200 50);
FORCEPROP 1 LAST PART_NUMBER 602433-106
J 0
(-200 100);
DISPLAY 0.617021 (-200 100);
PAINT BLUE (-200 100);
FORCEPROP 0 LAST BOM_SS E15431-004
J 0
(-256 -72);
DISPLAY 0.510638 (-256 -72);
PAINT BROWN (-256 -72);
DISPLAY BOTH (-256 -72);
FORCEPROP 2 LAST CDS_SEC 1
J 0
(-200 400);
PAINT ORANGE (-200 400);
DISPLAY INVISIBLE (-200 400);
FORCEPROP 2 LAST SEC_TYPE 0603V
J 0
(-200 450);
DISPLAY 1.021277 (-200 450);
PAINT ORANGE (-200 450);
DISPLAY INVISIBLE (-200 450);
FORCEPROP 2 LAST SEC 1
J 0
(-200 450);
DISPLAY 0.680851 (-200 450);
PAINT MONO (-200 450);
DISPLAY INVISIBLE (-200 450);
FORCEPROP 2 LAST CDS_LIB dev_discrete
J 0
(-250 250);
PAINT ORANGE (-250 250);
DISPLAY INVISIBLE (-250 250);
FORCEPROP 1 LAST PATH I281
J 0
(-200 400);
DISPLAY 0.978723 (-200 400);
PAINT WHITE (-200 400);
DISPLAY INVISIBLE (-200 400);
FORCEPROP 2 LAST CDS_LOCATION C2G4
J 0
(-200 350);
DISPLAY 0.617021 (-200 350);
PAINT AQUA (-200 350);
DISPLAY INVISIBLE (-200 350);
FORCEADD CAP_A..1
(75 250);
FORCEPROP 1 LAST TOLERANCE 20%
J 0
(125 200);
DISPLAY 0.617021 (125 200);
PAINT SKYBLUE (125 200);
FORCEPROP 1 LAST PART_NUMBER 602433-106
J 0
(125 100);
DISPLAY 0.617021 (125 100);
PAINT BLUE (125 100);
FORCEPROP 0 LAST GROUP PWR_MLCC_CAP
J 0
(131 -113);
DISPLAY 0.638298 (131 -113);
PAINT BROWN (131 -113);
DISPLAY BOTH (131 -113);
FORCEPROP 1 LAST VOLTAGE 4V
J 0
(125 250);
DISPLAY 0.617021 (125 250);
PAINT SKYBLUE (125 250);
FORCEPROP 1 LAST VALUE 47UF
J 0
(125 300);
DISPLAY 0.617021 (125 300);
PAINT SKYBLUE (125 300);
FORCEPROP 1 LASTPIN (75 350) $PN 1
J 0
(85 330);
DISPLAY 0.617021 (85 330);
PAINT ORANGE (85 330);
FORCEPROP 1 LAST LOCATION C2G5
J 0
(125 350);
DISPLAY 0.617021 (125 350);
PAINT AQUA (125 350);
FORCEPROP 1 LAST PACK_TYPE 0603V
J 0
(125 50);
DISPLAY 0.617021 (125 50);
PAINT SKYBLUE (125 50);
FORCEPROP 1 LASTPIN (75 150) $PN 2
J 0
(85 130);
DISPLAY 0.617021 (85 130);
PAINT ORANGE (85 130);
FORCEPROP 1 LAST MATERIAL X5R
J 0
(125 150);
DISPLAY 0.617021 (125 150);
PAINT SKYBLUE (125 150);
FORCEPROP 0 LAST BOM_SS E15431-004
J 0
(93 -12);
DISPLAY 0.510638 (93 -12);
PAINT BROWN (93 -12);
DISPLAY BOTH (93 -12);
FORCEPROP 2 LAST CDS_SEC 1
J 0
(125 400);
PAINT ORANGE (125 400);
DISPLAY INVISIBLE (125 400);
FORCEPROP 2 LAST SEC_TYPE 0603V
J 0
(125 450);
DISPLAY 1.021277 (125 450);
PAINT ORANGE (125 450);
DISPLAY INVISIBLE (125 450);
FORCEPROP 2 LAST SEC 1
J 0
(125 450);
DISPLAY 0.680851 (125 450);
PAINT MONO (125 450);
DISPLAY INVISIBLE (125 450);
FORCEPROP 2 LAST CDS_LIB dev_discrete
J 0
(75 250);
PAINT ORANGE (75 250);
DISPLAY INVISIBLE (75 250);
FORCEPROP 1 LAST PATH I282
J 0
(125 400);
DISPLAY 0.978723 (125 400);
PAINT WHITE (125 400);
DISPLAY INVISIBLE (125 400);
FORCEPROP 2 LAST CDS_LOCATION C2G5
J 0
(125 350);
DISPLAY 0.617021 (125 350);
PAINT AQUA (125 350);
DISPLAY INVISIBLE (125 350);
FORCEADD CAP_A..1
(375 250);
FORCEPROP 0 LAST GROUP PWR_MLCC_CAP
J 0
(456 -163);
DISPLAY 0.638298 (456 -163);
PAINT BROWN (456 -163);
DISPLAY BOTH (456 -163);
FORCEPROP 1 LASTPIN (375 350) $PN 1
J 0
(385 330);
DISPLAY 0.617021 (385 330);
PAINT ORANGE (385 330);
FORCEPROP 1 LASTPIN (375 150) $PN 2
J 0
(385 130);
DISPLAY 0.617021 (385 130);
PAINT ORANGE (385 130);
FORCEPROP 1 LAST TOLERANCE 20%
J 0
(425 200);
DISPLAY 0.617021 (425 200);
PAINT SKYBLUE (425 200);
FORCEPROP 1 LAST MATERIAL X5R
J 0
(425 150);
DISPLAY 0.617021 (425 150);
PAINT SKYBLUE (425 150);
FORCEPROP 1 LAST PACK_TYPE 0603V
J 0
(425 50);
DISPLAY 0.617021 (425 50);
PAINT SKYBLUE (425 50);
FORCEPROP 1 LAST PART_NUMBER 602433-106
J 0
(425 100);
DISPLAY 0.617021 (425 100);
PAINT BLUE (425 100);
FORCEPROP 1 LAST VOLTAGE 4V
J 0
(425 250);
DISPLAY 0.617021 (425 250);
PAINT SKYBLUE (425 250);
FORCEPROP 1 LAST VALUE 47UF
J 0
(425 300);
DISPLAY 0.617021 (425 300);
PAINT SKYBLUE (425 300);
FORCEPROP 1 LAST LOCATION C2G6
J 0
(425 350);
DISPLAY 0.617021 (425 350);
PAINT AQUA (425 350);
FORCEPROP 0 LAST BOM_SS E15431-004
J 0
(380 -77);
DISPLAY 0.510638 (380 -77);
PAINT BROWN (380 -77);
DISPLAY BOTH (380 -77);
FORCEPROP 2 LAST CDS_SEC 1
J 0
(425 400);
PAINT ORANGE (425 400);
DISPLAY INVISIBLE (425 400);
FORCEPROP 2 LAST SEC_TYPE 0603V
J 0
(425 450);
DISPLAY 1.021277 (425 450);
PAINT ORANGE (425 450);
DISPLAY INVISIBLE (425 450);
FORCEPROP 2 LAST SEC 1
J 0
(425 450);
DISPLAY 0.680851 (425 450);
PAINT MONO (425 450);
DISPLAY INVISIBLE (425 450);
FORCEPROP 2 LAST CDS_LIB dev_discrete
J 0
(375 250);
PAINT ORANGE (375 250);
DISPLAY INVISIBLE (375 250);
FORCEPROP 1 LAST PATH I283
J 0
(425 400);
DISPLAY 0.978723 (425 400);
PAINT WHITE (425 400);
DISPLAY INVISIBLE (425 400);
FORCEPROP 2 LAST CDS_LOCATION C2G6
J 0
(425 350);
DISPLAY 0.617021 (425 350);
PAINT AQUA (425 350);
DISPLAY INVISIBLE (425 350);
FORCEADD CAP_A..1
(675 250);
FORCEPROP 0 LAST GROUP PWR_MLCC_CAP
J 0
(731 -113);
DISPLAY 0.638298 (731 -113);
PAINT BROWN (731 -113);
DISPLAY BOTH (731 -113);
FORCEPROP 1 LAST VOLTAGE 4V
J 0
(725 250);
DISPLAY 0.617021 (725 250);
PAINT SKYBLUE (725 250);
FORCEPROP 1 LAST VALUE 47UF
J 0
(725 300);
DISPLAY 0.617021 (725 300);
PAINT SKYBLUE (725 300);
FORCEPROP 1 LASTPIN (675 350) $PN 1
J 0
(685 330);
DISPLAY 0.617021 (685 330);
PAINT ORANGE (685 330);
FORCEPROP 1 LASTPIN (675 150) $PN 2
J 0
(685 130);
DISPLAY 0.617021 (685 130);
PAINT ORANGE (685 130);
FORCEPROP 1 LAST TOLERANCE 20%
J 0
(725 200);
DISPLAY 0.617021 (725 200);
PAINT SKYBLUE (725 200);
FORCEPROP 1 LAST LOCATION C3G1
J 0
(725 350);
DISPLAY 0.617021 (725 350);
PAINT AQUA (725 350);
FORCEPROP 1 LAST MATERIAL X5R
J 0
(725 150);
DISPLAY 0.617021 (725 150);
PAINT SKYBLUE (725 150);
FORCEPROP 1 LAST PART_NUMBER 602433-106
J 0
(725 100);
DISPLAY 0.617021 (725 100);
PAINT BLUE (725 100);
FORCEPROP 1 LAST PACK_TYPE 0603V
J 0
(725 50);
DISPLAY 0.617021 (725 50);
PAINT SKYBLUE (725 50);
FORCEPROP 0 LAST BOM_SS E15431-004
J 0
(692 -23);
DISPLAY 0.510638 (692 -23);
PAINT BROWN (692 -23);
DISPLAY BOTH (692 -23);
FORCEPROP 2 LAST CDS_SEC 1
J 0
(725 400);
PAINT ORANGE (725 400);
DISPLAY INVISIBLE (725 400);
FORCEPROP 2 LAST SEC_TYPE 0603V
J 0
(725 450);
DISPLAY 1.021277 (725 450);
PAINT ORANGE (725 450);
DISPLAY INVISIBLE (725 450);
FORCEPROP 2 LAST SEC 1
J 0
(725 450);
DISPLAY 0.680851 (725 450);
PAINT MONO (725 450);
DISPLAY INVISIBLE (725 450);
FORCEPROP 2 LAST CDS_LIB dev_discrete
J 0
(675 250);
PAINT ORANGE (675 250);
DISPLAY INVISIBLE (675 250);
FORCEPROP 1 LAST PATH I284
J 0
(725 400);
DISPLAY 0.978723 (725 400);
PAINT WHITE (725 400);
DISPLAY INVISIBLE (725 400);
FORCEPROP 2 LAST CDS_LOCATION C3G1
J 0
(725 350);
DISPLAY 0.617021 (725 350);
PAINT AQUA (725 350);
DISPLAY INVISIBLE (725 350);
FORCEADD CAP_A..1
(950 250);
FORCEPROP 1 LAST PACK_TYPE 0603V
J 0
(1000 50);
DISPLAY 0.617021 (1000 50);
PAINT SKYBLUE (1000 50);
FORCEPROP 1 LAST PART_NUMBER 602433-106
J 0
(1000 100);
DISPLAY 0.617021 (1000 100);
PAINT BLUE (1000 100);
FORCEPROP 1 LAST MATERIAL X5R
J 0
(1000 150);
DISPLAY 0.617021 (1000 150);
PAINT SKYBLUE (1000 150);
FORCEPROP 0 LAST GROUP PWR_MLCC_CAP
J 0
(1006 -163);
DISPLAY 0.638298 (1006 -163);
PAINT BROWN (1006 -163);
DISPLAY BOTH (1006 -163);
FORCEPROP 1 LAST LOCATION C3G2
J 0
(1000 350);
DISPLAY 0.617021 (1000 350);
PAINT AQUA (1000 350);
FORCEPROP 1 LAST TOLERANCE 20%
J 0
(1000 200);
DISPLAY 0.617021 (1000 200);
PAINT SKYBLUE (1000 200);
FORCEPROP 1 LASTPIN (950 150) $PN 2
J 0
(960 130);
DISPLAY 0.617021 (960 130);
PAINT ORANGE (960 130);
FORCEPROP 1 LASTPIN (950 350) $PN 1
J 0
(960 330);
DISPLAY 0.617021 (960 330);
PAINT ORANGE (960 330);
FORCEPROP 1 LAST VALUE 47UF
J 0
(1000 300);
DISPLAY 0.617021 (1000 300);
PAINT SKYBLUE (1000 300);
FORCEPROP 1 LAST VOLTAGE 4V
J 0
(1000 250);
DISPLAY 0.617021 (1000 250);
PAINT SKYBLUE (1000 250);
FORCEPROP 0 LAST BOM_SS E15431-004
J 0
(966 -72);
DISPLAY 0.510638 (966 -72);
PAINT BROWN (966 -72);
DISPLAY BOTH (966 -72);
FORCEPROP 1 LAST PATH I285
J 0
(1000 400);
DISPLAY 0.978723 (1000 400);
PAINT WHITE (1000 400);
DISPLAY INVISIBLE (1000 400);
FORCEPROP 2 LAST CDS_LIB dev_discrete
J 0
(950 250);
PAINT ORANGE (950 250);
DISPLAY INVISIBLE (950 250);
FORCEPROP 2 LAST SEC 1
J 0
(1000 450);
DISPLAY 0.680851 (1000 450);
PAINT MONO (1000 450);
DISPLAY INVISIBLE (1000 450);
FORCEPROP 2 LAST SEC_TYPE 0603V
J 0
(1000 450);
DISPLAY 1.021277 (1000 450);
PAINT ORANGE (1000 450);
DISPLAY INVISIBLE (1000 450);
FORCEPROP 2 LAST CDS_SEC 1
J 0
(1000 400);
PAINT ORANGE (1000 400);
DISPLAY INVISIBLE (1000 400);
FORCEPROP 2 LAST CDS_LOCATION C3G2
J 0
(1000 350);
DISPLAY 0.617021 (1000 350);
PAINT AQUA (1000 350);
DISPLAY INVISIBLE (1000 350);
FORCEADD CAP_A..1
(1225 250);
FORCEPROP 1 LAST LOCATION C2G13
J 0
(1275 350);
DISPLAY 0.617021 (1275 350);
PAINT AQUA (1275 350);
FORCEPROP 1 LAST VALUE 47UF
J 0
(1275 300);
DISPLAY 0.617021 (1275 300);
PAINT SKYBLUE (1275 300);
FORCEPROP 0 LAST GROUP PWR_MLCC_CAP
J 0
(1281 -113);
DISPLAY 0.638298 (1281 -113);
PAINT BROWN (1281 -113);
DISPLAY BOTH (1281 -113);
FORCEPROP 1 LAST VOLTAGE 4V
J 0
(1275 250);
DISPLAY 0.617021 (1275 250);
PAINT SKYBLUE (1275 250);
FORCEPROP 1 LAST TOLERANCE 20%
J 0
(1275 200);
DISPLAY 0.617021 (1275 200);
PAINT SKYBLUE (1275 200);
FORCEPROP 1 LASTPIN (1225 350) $PN 1
J 0
(1235 330);
DISPLAY 0.617021 (1235 330);
PAINT ORANGE (1235 330);
FORCEPROP 1 LAST PACK_TYPE 0603V
J 0
(1275 50);
DISPLAY 0.617021 (1275 50);
PAINT SKYBLUE (1275 50);
FORCEPROP 1 LAST PART_NUMBER 602433-106
J 0
(1275 100);
DISPLAY 0.617021 (1275 100);
PAINT BLUE (1275 100);
FORCEPROP 1 LASTPIN (1225 150) $PN 2
J 0
(1235 130);
DISPLAY 0.617021 (1235 130);
PAINT ORANGE (1235 130);
FORCEPROP 1 LAST MATERIAL X5R
J 0
(1275 150);
DISPLAY 0.617021 (1275 150);
PAINT SKYBLUE (1275 150);
FORCEPROP 0 LAST BOM_SS E15431-004
J 0
(1219 -8);
DISPLAY 0.510638 (1219 -8);
PAINT BROWN (1219 -8);
DISPLAY BOTH (1219 -8);
FORCEPROP 2 LAST CDS_SEC 1
J 0
(1275 400);
PAINT ORANGE (1275 400);
DISPLAY INVISIBLE (1275 400);
FORCEPROP 2 LAST SEC_TYPE 0603V
J 0
(1275 450);
DISPLAY 1.021277 (1275 450);
PAINT ORANGE (1275 450);
DISPLAY INVISIBLE (1275 450);
FORCEPROP 2 LAST SEC 1
J 0
(1275 450);
DISPLAY 0.680851 (1275 450);
PAINT MONO (1275 450);
DISPLAY INVISIBLE (1275 450);
FORCEPROP 2 LAST CDS_LIB dev_discrete
J 0
(1225 250);
PAINT ORANGE (1225 250);
DISPLAY INVISIBLE (1225 250);
FORCEPROP 1 LAST PATH I286
J 0
(1275 400);
DISPLAY 0.978723 (1275 400);
PAINT WHITE (1275 400);
DISPLAY INVISIBLE (1275 400);
FORCEPROP 2 LAST CDS_LOCATION C2G13
J 0
(1275 350);
DISPLAY 0.617021 (1275 350);
PAINT AQUA (1275 350);
DISPLAY INVISIBLE (1275 350);
FORCEADD CAP_A..1
(1525 250);
FORCEPROP 0 LAST GROUP PWR_MLCC_CAP
J 0
(1581 -163);
DISPLAY 0.638298 (1581 -163);
PAINT BROWN (1581 -163);
DISPLAY BOTH (1581 -163);
FORCEPROP 1 LAST VOLTAGE 4V
J 0
(1575 250);
DISPLAY 0.617021 (1575 250);
PAINT SKYBLUE (1575 250);
FORCEPROP 1 LAST VALUE 47UF
J 0
(1575 300);
DISPLAY 0.617021 (1575 300);
PAINT SKYBLUE (1575 300);
FORCEPROP 1 LASTPIN (1525 350) $PN 1
J 0
(1535 330);
DISPLAY 0.617021 (1535 330);
PAINT ORANGE (1535 330);
FORCEPROP 1 LASTPIN (1525 150) $PN 2
J 0
(1535 130);
DISPLAY 0.617021 (1535 130);
PAINT ORANGE (1535 130);
FORCEPROP 1 LAST MATERIAL X5R
J 0
(1575 150);
DISPLAY 0.617021 (1575 150);
PAINT SKYBLUE (1575 150);
FORCEPROP 1 LAST TOLERANCE 20%
J 0
(1575 200);
DISPLAY 0.617021 (1575 200);
PAINT SKYBLUE (1575 200);
FORCEPROP 1 LAST LOCATION C2G14
J 0
(1575 350);
DISPLAY 0.617021 (1575 350);
PAINT AQUA (1575 350);
FORCEPROP 1 LAST PACK_TYPE 0603V
J 0
(1575 50);
DISPLAY 0.617021 (1575 50);
PAINT SKYBLUE (1575 50);
FORCEPROP 1 LAST PART_NUMBER 602433-106
J 0
(1575 100);
DISPLAY 0.617021 (1575 100);
PAINT BLUE (1575 100);
FORCEPROP 0 LAST BOM_SS E15431-004
J 0
(1521 -75);
DISPLAY 0.510638 (1521 -75);
PAINT BROWN (1521 -75);
DISPLAY BOTH (1521 -75);
FORCEPROP 2 LAST CDS_SEC 1
J 0
(1575 400);
PAINT ORANGE (1575 400);
DISPLAY INVISIBLE (1575 400);
FORCEPROP 2 LAST SEC_TYPE 0603V
J 0
(1575 450);
DISPLAY 1.021277 (1575 450);
PAINT ORANGE (1575 450);
DISPLAY INVISIBLE (1575 450);
FORCEPROP 2 LAST SEC 1
J 0
(1575 450);
DISPLAY 0.680851 (1575 450);
PAINT MONO (1575 450);
DISPLAY INVISIBLE (1575 450);
FORCEPROP 2 LAST CDS_LIB dev_discrete
J 0
(1525 250);
PAINT ORANGE (1525 250);
DISPLAY INVISIBLE (1525 250);
FORCEPROP 1 LAST PATH I287
J 0
(1575 400);
DISPLAY 0.978723 (1575 400);
PAINT WHITE (1575 400);
DISPLAY INVISIBLE (1575 400);
FORCEPROP 2 LAST CDS_LOCATION C2G14
J 0
(1575 350);
DISPLAY 0.617021 (1575 350);
PAINT AQUA (1575 350);
DISPLAY INVISIBLE (1575 350);
FORCEADD CAP_A..1
(1825 250);
FORCEPROP 1 LAST VOLTAGE 4V
J 0
(1875 250);
DISPLAY 0.617021 (1875 250);
PAINT SKYBLUE (1875 250);
FORCEPROP 1 LAST VALUE 47UF
J 0
(1875 300);
DISPLAY 0.617021 (1875 300);
PAINT SKYBLUE (1875 300);
FORCEPROP 1 LAST LOCATION C3G5
J 0
(1875 350);
DISPLAY 0.617021 (1875 350);
PAINT AQUA (1875 350);
FORCEPROP 1 LAST TOLERANCE 20%
J 0
(1875 200);
DISPLAY 0.617021 (1875 200);
PAINT SKYBLUE (1875 200);
FORCEPROP 1 LASTPIN (1825 350) $PN 1
J 0
(1835 330);
DISPLAY 0.617021 (1835 330);
PAINT ORANGE (1835 330);
FORCEPROP 0 LAST GROUP PWR_MLCC_CAP
J 0
(1881 -113);
DISPLAY 0.638298 (1881 -113);
PAINT BROWN (1881 -113);
DISPLAY BOTH (1881 -113);
FORCEPROP 1 LAST MATERIAL X5R
J 0
(1875 150);
DISPLAY 0.617021 (1875 150);
PAINT SKYBLUE (1875 150);
FORCEPROP 1 LAST PACK_TYPE 0603V
J 0
(1875 50);
DISPLAY 0.617021 (1875 50);
PAINT SKYBLUE (1875 50);
FORCEPROP 1 LAST PART_NUMBER 602433-106
J 0
(1875 100);
DISPLAY 0.617021 (1875 100);
PAINT BLUE (1875 100);
FORCEPROP 1 LASTPIN (1825 150) $PN 2
J 0
(1835 130);
DISPLAY 0.617021 (1835 130);
PAINT ORANGE (1835 130);
FORCEPROP 0 LAST BOM_SS E15431-004
J 0
(1836 -17);
DISPLAY 0.510638 (1836 -17);
PAINT BROWN (1836 -17);
DISPLAY BOTH (1836 -17);
FORCEPROP 2 LAST CDS_SEC 1
J 0
(1875 400);
PAINT ORANGE (1875 400);
DISPLAY INVISIBLE (1875 400);
FORCEPROP 2 LAST SEC_TYPE 0603V
J 0
(1875 450);
DISPLAY 1.021277 (1875 450);
PAINT ORANGE (1875 450);
DISPLAY INVISIBLE (1875 450);
FORCEPROP 2 LAST SEC 1
J 0
(1875 450);
DISPLAY 0.680851 (1875 450);
PAINT MONO (1875 450);
DISPLAY INVISIBLE (1875 450);
FORCEPROP 2 LAST CDS_LIB dev_discrete
J 0
(1825 250);
PAINT ORANGE (1825 250);
DISPLAY INVISIBLE (1825 250);
FORCEPROP 1 LAST PATH I288
J 0
(1875 400);
DISPLAY 0.978723 (1875 400);
PAINT WHITE (1875 400);
DISPLAY INVISIBLE (1875 400);
FORCEPROP 2 LAST CDS_LOCATION C3G5
J 0
(1875 350);
DISPLAY 0.617021 (1875 350);
PAINT AQUA (1875 350);
DISPLAY INVISIBLE (1875 350);
FORCEADD CAP_A..1
(2100 250);
FORCEPROP 1 LAST LOCATION C3G6
J 0
(2150 350);
DISPLAY 0.617021 (2150 350);
PAINT AQUA (2150 350);
FORCEPROP 1 LAST PACK_TYPE 0603V
J 0
(2150 50);
DISPLAY 0.617021 (2150 50);
PAINT SKYBLUE (2150 50);
FORCEPROP 1 LAST PART_NUMBER 602433-106
J 0
(2150 100);
DISPLAY 0.617021 (2150 100);
PAINT BLUE (2150 100);
FORCEPROP 1 LAST VALUE 47UF
J 0
(2150 300);
DISPLAY 0.617021 (2150 300);
PAINT SKYBLUE (2150 300);
FORCEPROP 1 LAST VOLTAGE 4V
J 0
(2150 250);
DISPLAY 0.617021 (2150 250);
PAINT SKYBLUE (2150 250);
FORCEPROP 1 LASTPIN (2100 350) $PN 1
J 0
(2110 330);
DISPLAY 0.617021 (2110 330);
PAINT ORANGE (2110 330);
FORCEPROP 1 LASTPIN (2100 150) $PN 2
J 0
(2110 130);
DISPLAY 0.617021 (2110 130);
PAINT ORANGE (2110 130);
FORCEPROP 1 LAST MATERIAL X5R
J 0
(2150 150);
DISPLAY 0.617021 (2150 150);
PAINT SKYBLUE (2150 150);
FORCEPROP 1 LAST TOLERANCE 20%
J 0
(2150 200);
DISPLAY 0.617021 (2150 200);
PAINT SKYBLUE (2150 200);
FORCEPROP 0 LAST BOM_SS E15431-004
J 0
(2095 -81);
DISPLAY 0.510638 (2095 -81);
PAINT BROWN (2095 -81);
DISPLAY BOTH (2095 -81);
FORCEPROP 0 LAST GROUP PWR_MLCC_CAP
J 0
(2156 -163);
DISPLAY 0.638298 (2156 -163);
PAINT BROWN (2156 -163);
DISPLAY BOTH (2156 -163);
FORCEPROP 2 LAST CDS_SEC 1
J 0
(2150 400);
PAINT ORANGE (2150 400);
DISPLAY INVISIBLE (2150 400);
FORCEPROP 2 LAST SEC_TYPE 0603V
J 0
(2150 450);
DISPLAY 1.021277 (2150 450);
PAINT ORANGE (2150 450);
DISPLAY INVISIBLE (2150 450);
FORCEPROP 2 LAST SEC 1
J 0
(2150 450);
DISPLAY 0.680851 (2150 450);
PAINT MONO (2150 450);
DISPLAY INVISIBLE (2150 450);
FORCEPROP 2 LAST CDS_LIB dev_discrete
J 0
(2100 250);
PAINT ORANGE (2100 250);
DISPLAY INVISIBLE (2100 250);
FORCEPROP 1 LAST PATH I289
J 0
(2150 400);
DISPLAY 0.978723 (2150 400);
PAINT WHITE (2150 400);
DISPLAY INVISIBLE (2150 400);
FORCEPROP 2 LAST CDS_LOCATION C3G6
J 0
(2150 350);
DISPLAY 0.617021 (2150 350);
PAINT AQUA (2150 350);
DISPLAY INVISIBLE (2150 350);
FORCEADD CAP_A..1
(-2250 -450);
FORCEPROP 0 LAST GROUP PWR_MLCC_CAP
J 0
(-2194 -688);
DISPLAY 0.638298 (-2194 -688);
PAINT BROWN (-2194 -688);
DISPLAY BOTH (-2194 -688);
FORCEPROP 1 LAST VALUE 47UF
J 0
(-2200 -400);
DISPLAY 0.617021 (-2200 -400);
PAINT SKYBLUE (-2200 -400);
FORCEPROP 1 LAST VOLTAGE 4V
J 0
(-2200 -450);
DISPLAY 0.617021 (-2200 -450);
PAINT SKYBLUE (-2200 -450);
FORCEPROP 1 LAST TOLERANCE 20%
J 0
(-2200 -500);
DISPLAY 0.617021 (-2200 -500);
PAINT SKYBLUE (-2200 -500);
FORCEPROP 1 LAST MATERIAL X5R
J 0
(-2200 -550);
DISPLAY 0.617021 (-2200 -550);
PAINT SKYBLUE (-2200 -550);
FORCEPROP 1 LAST PACK_TYPE 0603V
J 0
(-2200 -650);
DISPLAY 0.617021 (-2200 -650);
PAINT SKYBLUE (-2200 -650);
FORCEPROP 1 LAST PART_NUMBER 602433-106
J 0
(-2200 -600);
DISPLAY 0.617021 (-2200 -600);
PAINT BLUE (-2200 -600);
FORCEPROP 1 LAST LOCATION C8U7
J 0
(-2200 -350);
DISPLAY 0.617021 (-2200 -350);
PAINT AQUA (-2200 -350);
FORCEPROP 1 LASTPIN (-2250 -350) $PN 1
J 0
(-2240 -370);
DISPLAY 0.617021 (-2240 -370);
PAINT ORANGE (-2240 -370);
FORCEPROP 1 LASTPIN (-2250 -550) $PN 2
J 0
(-2240 -570);
DISPLAY 0.617021 (-2240 -570);
PAINT ORANGE (-2240 -570);
FORCEPROP 0 LAST BOM_SS E15431-004
J 0
(-2235 -734);
DISPLAY 0.510638 (-2235 -734);
PAINT BROWN (-2235 -734);
DISPLAY BOTH (-2235 -734);
FORCEPROP 1 LAST PATH I290
J 0
(-2200 -300);
DISPLAY 0.978723 (-2200 -300);
PAINT WHITE (-2200 -300);
DISPLAY INVISIBLE (-2200 -300);
FORCEPROP 2 LAST CDS_LIB dev_discrete
J 0
(-2250 -450);
PAINT ORANGE (-2250 -450);
DISPLAY INVISIBLE (-2250 -450);
FORCEPROP 2 LAST SEC 1
J 0
(-2200 -250);
DISPLAY 0.680851 (-2200 -250);
PAINT MONO (-2200 -250);
DISPLAY INVISIBLE (-2200 -250);
FORCEPROP 2 LAST SEC_TYPE 0603V
J 0
(-2200 -250);
DISPLAY 1.021277 (-2200 -250);
PAINT ORANGE (-2200 -250);
DISPLAY INVISIBLE (-2200 -250);
FORCEPROP 2 LAST CDS_SEC 1
J 0
(-2200 -300);
PAINT ORANGE (-2200 -300);
DISPLAY INVISIBLE (-2200 -300);
FORCEPROP 2 LAST CDS_LOCATION C8U7
J 0
(-2200 -350);
DISPLAY 0.617021 (-2200 -350);
PAINT AQUA (-2200 -350);
DISPLAY INVISIBLE (-2200 -350);
FORCEADD CAP_A..1
(-1950 -450);
FORCEPROP 0 LAST GROUP PWR_MLCC_CAP
J 0
(-1894 -838);
DISPLAY 0.638298 (-1894 -838);
PAINT BROWN (-1894 -838);
DISPLAY BOTH (-1894 -838);
FORCEPROP 1 LAST TOLERANCE 20%
J 0
(-1900 -500);
DISPLAY 0.617021 (-1900 -500);
PAINT SKYBLUE (-1900 -500);
FORCEPROP 1 LAST MATERIAL X5R
J 0
(-1900 -550);
DISPLAY 0.617021 (-1900 -550);
PAINT SKYBLUE (-1900 -550);
FORCEPROP 1 LAST VOLTAGE 4V
J 0
(-1900 -450);
DISPLAY 0.617021 (-1900 -450);
PAINT SKYBLUE (-1900 -450);
FORCEPROP 1 LAST PART_NUMBER 602433-106
J 0
(-1900 -600);
DISPLAY 0.617021 (-1900 -600);
PAINT BLUE (-1900 -600);
FORCEPROP 1 LAST PACK_TYPE 0603V
J 0
(-1900 -650);
DISPLAY 0.617021 (-1900 -650);
PAINT SKYBLUE (-1900 -650);
FORCEPROP 1 LASTPIN (-1950 -550) $PN 2
J 0
(-1940 -570);
DISPLAY 0.617021 (-1940 -570);
PAINT ORANGE (-1940 -570);
FORCEPROP 1 LAST LOCATION C8U2
J 0
(-1900 -350);
DISPLAY 0.617021 (-1900 -350);
PAINT AQUA (-1900 -350);
FORCEPROP 1 LAST VALUE 47UF
J 0
(-1900 -400);
DISPLAY 0.617021 (-1900 -400);
PAINT SKYBLUE (-1900 -400);
FORCEPROP 1 LASTPIN (-1950 -350) $PN 1
J 0
(-1940 -370);
DISPLAY 0.617021 (-1940 -370);
PAINT ORANGE (-1940 -370);
FORCEPROP 0 LAST BOM_SS E15431-004
J 0
(-1958 -784);
DISPLAY 0.510638 (-1958 -784);
PAINT BROWN (-1958 -784);
DISPLAY BOTH (-1958 -784);
FORCEPROP 1 LAST PATH I291
J 0
(-1900 -300);
DISPLAY 0.978723 (-1900 -300);
PAINT WHITE (-1900 -300);
DISPLAY INVISIBLE (-1900 -300);
FORCEPROP 2 LAST CDS_SEC 1
J 0
(-1900 -300);
PAINT ORANGE (-1900 -300);
DISPLAY INVISIBLE (-1900 -300);
FORCEPROP 2 LAST SEC_TYPE 0603V
J 0
(-1900 -250);
DISPLAY 1.021277 (-1900 -250);
PAINT ORANGE (-1900 -250);
DISPLAY INVISIBLE (-1900 -250);
FORCEPROP 2 LAST SEC 1
J 0
(-1900 -250);
DISPLAY 0.680851 (-1900 -250);
PAINT MONO (-1900 -250);
DISPLAY INVISIBLE (-1900 -250);
FORCEPROP 2 LAST CDS_LIB dev_discrete
J 0
(-1950 -450);
PAINT ORANGE (-1950 -450);
DISPLAY INVISIBLE (-1950 -450);
FORCEPROP 2 LAST CDS_LOCATION C8U2
J 0
(-1900 -350);
DISPLAY 0.617021 (-1900 -350);
PAINT AQUA (-1900 -350);
DISPLAY INVISIBLE (-1900 -350);
FORCEADD CAP_A..1
(-1650 -450);
FORCEPROP 0 LAST GROUP PWR_MLCC_CAP
J 0
(-1594 -688);
DISPLAY 0.638298 (-1594 -688);
PAINT BROWN (-1594 -688);
DISPLAY BOTH (-1594 -688);
FORCEPROP 1 LAST VALUE 47UF
J 0
(-1600 -400);
DISPLAY 0.617021 (-1600 -400);
PAINT SKYBLUE (-1600 -400);
FORCEPROP 1 LASTPIN (-1650 -350) $PN 1
J 0
(-1640 -370);
DISPLAY 0.617021 (-1640 -370);
PAINT ORANGE (-1640 -370);
FORCEPROP 1 LASTPIN (-1650 -550) $PN 2
J 0
(-1640 -570);
DISPLAY 0.617021 (-1640 -570);
PAINT ORANGE (-1640 -570);
FORCEPROP 1 LAST TOLERANCE 20%
J 0
(-1600 -500);
DISPLAY 0.617021 (-1600 -500);
PAINT SKYBLUE (-1600 -500);
FORCEPROP 1 LAST LOCATION C7U2
J 0
(-1600 -350);
DISPLAY 0.617021 (-1600 -350);
PAINT AQUA (-1600 -350);
FORCEPROP 1 LAST PACK_TYPE 0603V
J 0
(-1600 -650);
DISPLAY 0.617021 (-1600 -650);
PAINT SKYBLUE (-1600 -650);
FORCEPROP 1 LAST MATERIAL X5R
J 0
(-1600 -550);
DISPLAY 0.617021 (-1600 -550);
PAINT SKYBLUE (-1600 -550);
FORCEPROP 1 LAST PART_NUMBER 602433-106
J 0
(-1600 -600);
DISPLAY 0.617021 (-1600 -600);
PAINT BLUE (-1600 -600);
FORCEPROP 1 LAST VOLTAGE 4V
J 0
(-1600 -450);
DISPLAY 0.617021 (-1600 -450);
PAINT SKYBLUE (-1600 -450);
FORCEPROP 0 LAST BOM_SS E15431-004
J 0
(-1631 -751);
DISPLAY 0.510638 (-1631 -751);
PAINT BROWN (-1631 -751);
DISPLAY BOTH (-1631 -751);
FORCEPROP 1 LAST PATH I292
J 0
(-1600 -300);
DISPLAY 0.978723 (-1600 -300);
PAINT WHITE (-1600 -300);
DISPLAY INVISIBLE (-1600 -300);
FORCEPROP 2 LAST CDS_SEC 1
J 0
(-1600 -300);
PAINT ORANGE (-1600 -300);
DISPLAY INVISIBLE (-1600 -300);
FORCEPROP 2 LAST SEC_TYPE 0603V
J 0
(-1600 -250);
DISPLAY 1.021277 (-1600 -250);
PAINT ORANGE (-1600 -250);
DISPLAY INVISIBLE (-1600 -250);
FORCEPROP 2 LAST SEC 1
J 0
(-1600 -250);
DISPLAY 0.680851 (-1600 -250);
PAINT MONO (-1600 -250);
DISPLAY INVISIBLE (-1600 -250);
FORCEPROP 2 LAST CDS_LIB dev_discrete
J 0
(-1650 -450);
PAINT ORANGE (-1650 -450);
DISPLAY INVISIBLE (-1650 -450);
FORCEPROP 2 LAST CDS_LOCATION C7U2
J 0
(-1600 -350);
DISPLAY 0.617021 (-1600 -350);
PAINT AQUA (-1600 -350);
DISPLAY INVISIBLE (-1600 -350);
FORCEADD CAP_A..1
(-1375 -450);
FORCEPROP 0 LAST GROUP PWR_MLCC_CAP
J 0
(-1319 -838);
DISPLAY 0.638298 (-1319 -838);
PAINT BROWN (-1319 -838);
DISPLAY BOTH (-1319 -838);
FORCEPROP 1 LAST LOCATION C7U1
J 0
(-1325 -350);
DISPLAY 0.617021 (-1325 -350);
PAINT AQUA (-1325 -350);
FORCEPROP 1 LAST TOLERANCE 20%
J 0
(-1325 -500);
DISPLAY 0.617021 (-1325 -500);
PAINT SKYBLUE (-1325 -500);
FORCEPROP 1 LASTPIN (-1375 -550) $PN 2
J 0
(-1365 -570);
DISPLAY 0.617021 (-1365 -570);
PAINT ORANGE (-1365 -570);
FORCEPROP 1 LASTPIN (-1375 -350) $PN 1
J 0
(-1365 -370);
DISPLAY 0.617021 (-1365 -370);
PAINT ORANGE (-1365 -370);
FORCEPROP 1 LAST PACK_TYPE 0603V
J 0
(-1325 -650);
DISPLAY 0.617021 (-1325 -650);
PAINT SKYBLUE (-1325 -650);
FORCEPROP 1 LAST PART_NUMBER 602433-106
J 0
(-1325 -600);
DISPLAY 0.617021 (-1325 -600);
PAINT BLUE (-1325 -600);
FORCEPROP 1 LAST MATERIAL X5R
J 0
(-1325 -550);
DISPLAY 0.617021 (-1325 -550);
PAINT SKYBLUE (-1325 -550);
FORCEPROP 1 LAST VALUE 47UF
J 0
(-1325 -400);
DISPLAY 0.617021 (-1325 -400);
PAINT SKYBLUE (-1325 -400);
FORCEPROP 1 LAST VOLTAGE 4V
J 0
(-1325 -450);
DISPLAY 0.617021 (-1325 -450);
PAINT SKYBLUE (-1325 -450);
FORCEPROP 0 LAST BOM_SS E15431-004
J 0
(-1373 -789);
DISPLAY 0.510638 (-1373 -789);
PAINT BROWN (-1373 -789);
DISPLAY BOTH (-1373 -789);
FORCEPROP 1 LAST PATH I293
J 0
(-1325 -300);
DISPLAY 0.978723 (-1325 -300);
PAINT WHITE (-1325 -300);
DISPLAY INVISIBLE (-1325 -300);
FORCEPROP 2 LAST CDS_LIB dev_discrete
J 0
(-1375 -450);
PAINT ORANGE (-1375 -450);
DISPLAY INVISIBLE (-1375 -450);
FORCEPROP 2 LAST SEC 1
J 0
(-1325 -250);
DISPLAY 0.680851 (-1325 -250);
PAINT MONO (-1325 -250);
DISPLAY INVISIBLE (-1325 -250);
FORCEPROP 2 LAST SEC_TYPE 0603V
J 0
(-1325 -250);
DISPLAY 1.021277 (-1325 -250);
PAINT ORANGE (-1325 -250);
DISPLAY INVISIBLE (-1325 -250);
FORCEPROP 2 LAST CDS_SEC 1
J 0
(-1325 -300);
PAINT ORANGE (-1325 -300);
DISPLAY INVISIBLE (-1325 -300);
FORCEPROP 2 LAST CDS_LOCATION C7U1
J 0
(-1325 -350);
DISPLAY 0.617021 (-1325 -350);
PAINT AQUA (-1325 -350);
DISPLAY INVISIBLE (-1325 -350);
FORCEADD CAP_A..1
(-1100 -450);
FORCEPROP 0 LAST GROUP PWR_MLCC_CAP
J 0
(-1044 -713);
DISPLAY 0.638298 (-1044 -713);
PAINT BROWN (-1044 -713);
DISPLAY BOTH (-1044 -713);
FORCEPROP 1 LAST PACK_TYPE 0603V
J 0
(-1050 -650);
DISPLAY 0.617021 (-1050 -650);
PAINT SKYBLUE (-1050 -650);
FORCEPROP 1 LASTPIN (-1100 -350) $PN 1
J 0
(-1090 -370);
DISPLAY 0.617021 (-1090 -370);
PAINT ORANGE (-1090 -370);
FORCEPROP 1 LASTPIN (-1100 -550) $PN 2
J 0
(-1090 -570);
DISPLAY 0.617021 (-1090 -570);
PAINT ORANGE (-1090 -570);
FORCEPROP 1 LAST MATERIAL X5R
J 0
(-1050 -550);
DISPLAY 0.617021 (-1050 -550);
PAINT SKYBLUE (-1050 -550);
FORCEPROP 1 LAST TOLERANCE 20%
J 0
(-1050 -500);
DISPLAY 0.617021 (-1050 -500);
PAINT SKYBLUE (-1050 -500);
FORCEPROP 1 LAST LOCATION C8U3
J 0
(-1050 -350);
DISPLAY 0.617021 (-1050 -350);
PAINT AQUA (-1050 -350);
FORCEPROP 1 LAST PART_NUMBER 602433-106
J 0
(-1050 -600);
DISPLAY 0.617021 (-1050 -600);
PAINT BLUE (-1050 -600);
FORCEPROP 1 LAST VALUE 47UF
J 0
(-1050 -400);
DISPLAY 0.617021 (-1050 -400);
PAINT SKYBLUE (-1050 -400);
FORCEPROP 1 LAST VOLTAGE 4V
J 0
(-1050 -450);
DISPLAY 0.617021 (-1050 -450);
PAINT SKYBLUE (-1050 -450);
FORCEPROP 0 LAST BOM_SS E15431-004
J 0
(-1099 -751);
DISPLAY 0.510638 (-1099 -751);
PAINT BROWN (-1099 -751);
DISPLAY BOTH (-1099 -751);
FORCEPROP 1 LAST PATH I294
J 0
(-1050 -300);
DISPLAY 0.978723 (-1050 -300);
PAINT WHITE (-1050 -300);
DISPLAY INVISIBLE (-1050 -300);
FORCEPROP 2 LAST CDS_SEC 1
J 0
(-1050 -300);
PAINT ORANGE (-1050 -300);
DISPLAY INVISIBLE (-1050 -300);
FORCEPROP 2 LAST SEC_TYPE 0603V
J 0
(-1050 -250);
DISPLAY 1.021277 (-1050 -250);
PAINT ORANGE (-1050 -250);
DISPLAY INVISIBLE (-1050 -250);
FORCEPROP 2 LAST SEC 1
J 0
(-1050 -250);
DISPLAY 0.680851 (-1050 -250);
PAINT MONO (-1050 -250);
DISPLAY INVISIBLE (-1050 -250);
FORCEPROP 2 LAST CDS_LIB dev_discrete
J 0
(-1100 -450);
PAINT ORANGE (-1100 -450);
DISPLAY INVISIBLE (-1100 -450);
FORCEPROP 2 LAST CDS_LOCATION C8U3
J 0
(-1050 -350);
DISPLAY 0.617021 (-1050 -350);
PAINT AQUA (-1050 -350);
DISPLAY INVISIBLE (-1050 -350);
FORCEADD CAP_A..1
(-800 -450);
FORCEPROP 0 LAST GROUP PWR_MLCC_CAP
J 0
(-744 -838);
DISPLAY 0.638298 (-744 -838);
PAINT BROWN (-744 -838);
DISPLAY BOTH (-744 -838);
FORCEPROP 1 LAST LOCATION C7T4
J 0
(-750 -350);
DISPLAY 0.617021 (-750 -350);
PAINT AQUA (-750 -350);
FORCEPROP 1 LAST TOLERANCE 20%
J 0
(-750 -500);
DISPLAY 0.617021 (-750 -500);
PAINT SKYBLUE (-750 -500);
FORCEPROP 1 LAST MATERIAL X5R
J 0
(-750 -550);
DISPLAY 0.617021 (-750 -550);
PAINT SKYBLUE (-750 -550);
FORCEPROP 1 LASTPIN (-800 -550) $PN 2
J 0
(-790 -570);
DISPLAY 0.617021 (-790 -570);
PAINT ORANGE (-790 -570);
FORCEPROP 1 LASTPIN (-800 -350) $PN 1
J 0
(-790 -370);
DISPLAY 0.617021 (-790 -370);
PAINT ORANGE (-790 -370);
FORCEPROP 1 LAST PACK_TYPE 0603V
J 0
(-750 -650);
DISPLAY 0.617021 (-750 -650);
PAINT SKYBLUE (-750 -650);
FORCEPROP 1 LAST PART_NUMBER 602433-106
J 0
(-750 -600);
DISPLAY 0.617021 (-750 -600);
PAINT BLUE (-750 -600);
FORCEPROP 1 LAST VOLTAGE 4V
J 0
(-750 -450);
DISPLAY 0.617021 (-750 -450);
PAINT SKYBLUE (-750 -450);
FORCEPROP 1 LAST VALUE 47UF
J 0
(-750 -400);
DISPLAY 0.617021 (-750 -400);
PAINT SKYBLUE (-750 -400);
FORCEPROP 0 LAST BOM_SS E15431-004
J 0
(-803 -806);
DISPLAY 0.510638 (-803 -806);
PAINT BROWN (-803 -806);
DISPLAY BOTH (-803 -806);
FORCEPROP 1 LAST PATH I295
J 0
(-750 -300);
DISPLAY 0.978723 (-750 -300);
PAINT WHITE (-750 -300);
DISPLAY INVISIBLE (-750 -300);
FORCEPROP 2 LAST CDS_LIB dev_discrete
J 0
(-800 -450);
PAINT ORANGE (-800 -450);
DISPLAY INVISIBLE (-800 -450);
FORCEPROP 2 LAST SEC 1
J 0
(-750 -250);
DISPLAY 0.680851 (-750 -250);
PAINT MONO (-750 -250);
DISPLAY INVISIBLE (-750 -250);
FORCEPROP 2 LAST SEC_TYPE 0603V
J 0
(-750 -250);
DISPLAY 1.021277 (-750 -250);
PAINT ORANGE (-750 -250);
DISPLAY INVISIBLE (-750 -250);
FORCEPROP 2 LAST CDS_SEC 1
J 0
(-750 -300);
PAINT ORANGE (-750 -300);
DISPLAY INVISIBLE (-750 -300);
FORCEPROP 2 LAST CDS_LOCATION C7T4
J 0
(-750 -350);
DISPLAY 0.617021 (-750 -350);
PAINT AQUA (-750 -350);
DISPLAY INVISIBLE (-750 -350);
FORCEADD CAP_A..1
(-500 -450);
FORCEPROP 0 LAST GROUP PWR_MLCC_CAP
J 0
(-444 -688);
DISPLAY 0.638298 (-444 -688);
PAINT BROWN (-444 -688);
DISPLAY BOTH (-444 -688);
FORCEPROP 1 LAST LOCATION C7T5
J 0
(-450 -350);
DISPLAY 0.617021 (-450 -350);
PAINT AQUA (-450 -350);
FORCEPROP 1 LAST VOLTAGE 4V
J 0
(-450 -450);
DISPLAY 0.617021 (-450 -450);
PAINT SKYBLUE (-450 -450);
FORCEPROP 1 LAST PART_NUMBER 602433-106
J 0
(-450 -600);
DISPLAY 0.617021 (-450 -600);
PAINT BLUE (-450 -600);
FORCEPROP 1 LAST PACK_TYPE 0603V
J 0
(-450 -650);
DISPLAY 0.617021 (-450 -650);
PAINT SKYBLUE (-450 -650);
FORCEPROP 1 LASTPIN (-500 -350) $PN 1
J 0
(-490 -370);
DISPLAY 0.617021 (-490 -370);
PAINT ORANGE (-490 -370);
FORCEPROP 1 LASTPIN (-500 -550) $PN 2
J 0
(-490 -570);
DISPLAY 0.617021 (-490 -570);
PAINT ORANGE (-490 -570);
FORCEPROP 1 LAST MATERIAL X5R
J 0
(-450 -550);
DISPLAY 0.617021 (-450 -550);
PAINT SKYBLUE (-450 -550);
FORCEPROP 1 LAST TOLERANCE 20%
J 0
(-450 -500);
DISPLAY 0.617021 (-450 -500);
PAINT SKYBLUE (-450 -500);
FORCEPROP 1 LAST VALUE 47UF
J 0
(-450 -400);
DISPLAY 0.617021 (-450 -400);
PAINT SKYBLUE (-450 -400);
FORCEPROP 0 LAST BOM_SS E15431-004
J 0
(-506 -740);
DISPLAY 0.510638 (-506 -740);
PAINT BROWN (-506 -740);
DISPLAY BOTH (-506 -740);
FORCEPROP 1 LAST PATH I296
J 0
(-450 -300);
DISPLAY 0.978723 (-450 -300);
PAINT WHITE (-450 -300);
DISPLAY INVISIBLE (-450 -300);
FORCEPROP 2 LAST CDS_SEC 1
J 0
(-450 -300);
PAINT ORANGE (-450 -300);
DISPLAY INVISIBLE (-450 -300);
FORCEPROP 2 LAST SEC_TYPE 0603V
J 0
(-450 -250);
DISPLAY 1.021277 (-450 -250);
PAINT ORANGE (-450 -250);
DISPLAY INVISIBLE (-450 -250);
FORCEPROP 2 LAST SEC 1
J 0
(-450 -250);
DISPLAY 0.680851 (-450 -250);
PAINT MONO (-450 -250);
DISPLAY INVISIBLE (-450 -250);
FORCEPROP 2 LAST CDS_LIB dev_discrete
J 0
(-500 -450);
PAINT ORANGE (-500 -450);
DISPLAY INVISIBLE (-500 -450);
FORCEPROP 2 LAST CDS_LOCATION C7T5
J 0
(-450 -350);
DISPLAY 0.617021 (-450 -350);
PAINT AQUA (-450 -350);
DISPLAY INVISIBLE (-450 -350);
FORCEADD CAP_A..1
(-225 -450);
FORCEPROP 0 LAST GROUP PWR_MLCC_CAP
J 0
(-169 -838);
DISPLAY 0.638298 (-169 -838);
PAINT BROWN (-169 -838);
DISPLAY BOTH (-169 -838);
FORCEPROP 1 LAST LOCATION C8T5
J 0
(-175 -350);
DISPLAY 0.617021 (-175 -350);
PAINT AQUA (-175 -350);
FORCEPROP 1 LAST TOLERANCE 20%
J 0
(-175 -500);
DISPLAY 0.617021 (-175 -500);
PAINT SKYBLUE (-175 -500);
FORCEPROP 1 LAST MATERIAL X5R
J 0
(-175 -550);
DISPLAY 0.617021 (-175 -550);
PAINT SKYBLUE (-175 -550);
FORCEPROP 1 LASTPIN (-225 -550) $PN 2
J 0
(-215 -570);
DISPLAY 0.617021 (-215 -570);
PAINT ORANGE (-215 -570);
FORCEPROP 1 LASTPIN (-225 -350) $PN 1
J 0
(-215 -370);
DISPLAY 0.617021 (-215 -370);
PAINT ORANGE (-215 -370);
FORCEPROP 1 LAST PACK_TYPE 0603V
J 0
(-175 -650);
DISPLAY 0.617021 (-175 -650);
PAINT SKYBLUE (-175 -650);
FORCEPROP 1 LAST PART_NUMBER 602433-106
J 0
(-175 -600);
DISPLAY 0.617021 (-175 -600);
PAINT BLUE (-175 -600);
FORCEPROP 1 LAST VOLTAGE 4V
J 0
(-175 -450);
DISPLAY 0.617021 (-175 -450);
PAINT SKYBLUE (-175 -450);
FORCEPROP 1 LAST VALUE 47UF
J 0
(-175 -400);
DISPLAY 0.617021 (-175 -400);
PAINT SKYBLUE (-175 -400);
FORCEPROP 0 LAST BOM_SS E15431-004
J 0
(-225 -792);
DISPLAY 0.510638 (-225 -792);
PAINT BROWN (-225 -792);
DISPLAY BOTH (-225 -792);
FORCEPROP 1 LAST PATH I297
J 0
(-175 -300);
DISPLAY 0.978723 (-175 -300);
PAINT WHITE (-175 -300);
DISPLAY INVISIBLE (-175 -300);
FORCEPROP 2 LAST CDS_LIB dev_discrete
J 0
(-225 -450);
PAINT ORANGE (-225 -450);
DISPLAY INVISIBLE (-225 -450);
FORCEPROP 2 LAST SEC 1
J 0
(-175 -250);
DISPLAY 0.680851 (-175 -250);
PAINT MONO (-175 -250);
DISPLAY INVISIBLE (-175 -250);
FORCEPROP 2 LAST SEC_TYPE 0603V
J 0
(-175 -250);
DISPLAY 1.021277 (-175 -250);
PAINT ORANGE (-175 -250);
DISPLAY INVISIBLE (-175 -250);
FORCEPROP 2 LAST CDS_SEC 1
J 0
(-175 -300);
PAINT ORANGE (-175 -300);
DISPLAY INVISIBLE (-175 -300);
FORCEPROP 2 LAST CDS_LOCATION C8T5
J 0
(-175 -350);
DISPLAY 0.617021 (-175 -350);
PAINT AQUA (-175 -350);
DISPLAY INVISIBLE (-175 -350);
FORCEADD CAP_A..1
(100 -450);
FORCEPROP 0 LAST GROUP PWR_MLCC_CAP
J 0
(156 -688);
DISPLAY 0.638298 (156 -688);
PAINT BROWN (156 -688);
DISPLAY BOTH (156 -688);
FORCEPROP 1 LAST VOLTAGE 4V
J 0
(150 -450);
DISPLAY 0.617021 (150 -450);
PAINT SKYBLUE (150 -450);
FORCEPROP 1 LAST PART_NUMBER 602433-106
J 0
(150 -600);
DISPLAY 0.617021 (150 -600);
PAINT BLUE (150 -600);
FORCEPROP 1 LAST VALUE 47UF
J 0
(150 -400);
DISPLAY 0.617021 (150 -400);
PAINT SKYBLUE (150 -400);
FORCEPROP 1 LAST PACK_TYPE 0603V
J 0
(150 -650);
DISPLAY 0.617021 (150 -650);
PAINT SKYBLUE (150 -650);
FORCEPROP 1 LASTPIN (100 -350) $PN 1
J 0
(110 -370);
DISPLAY 0.617021 (110 -370);
PAINT ORANGE (110 -370);
FORCEPROP 1 LASTPIN (100 -550) $PN 2
J 0
(110 -570);
DISPLAY 0.617021 (110 -570);
PAINT ORANGE (110 -570);
FORCEPROP 1 LAST MATERIAL X5R
J 0
(150 -550);
DISPLAY 0.617021 (150 -550);
PAINT SKYBLUE (150 -550);
FORCEPROP 1 LAST TOLERANCE 20%
J 0
(150 -500);
DISPLAY 0.617021 (150 -500);
PAINT SKYBLUE (150 -500);
FORCEPROP 1 LAST LOCATION C8U6
J 0
(150 -350);
DISPLAY 0.617021 (150 -350);
PAINT AQUA (150 -350);
FORCEPROP 0 LAST BOM_SS E15431-004
J 0
(78 -740);
DISPLAY 0.510638 (78 -740);
PAINT BROWN (78 -740);
DISPLAY BOTH (78 -740);
FORCEPROP 1 LAST PATH I298
J 0
(150 -300);
DISPLAY 0.978723 (150 -300);
PAINT WHITE (150 -300);
DISPLAY INVISIBLE (150 -300);
FORCEPROP 2 LAST CDS_SEC 1
J 0
(150 -300);
PAINT ORANGE (150 -300);
DISPLAY INVISIBLE (150 -300);
FORCEPROP 2 LAST SEC_TYPE 0603V
J 0
(150 -250);
DISPLAY 1.021277 (150 -250);
PAINT ORANGE (150 -250);
DISPLAY INVISIBLE (150 -250);
FORCEPROP 2 LAST SEC 1
J 0
(150 -250);
DISPLAY 0.680851 (150 -250);
PAINT MONO (150 -250);
DISPLAY INVISIBLE (150 -250);
FORCEPROP 2 LAST CDS_LIB dev_discrete
J 0
(100 -450);
PAINT ORANGE (100 -450);
DISPLAY INVISIBLE (100 -450);
FORCEPROP 2 LAST CDS_LOCATION C8U6
J 0
(150 -350);
DISPLAY 0.617021 (150 -350);
PAINT AQUA (150 -350);
DISPLAY INVISIBLE (150 -350);
FORCEADD CAP_A..1
(400 -450);
FORCEPROP 0 LAST GROUP PWR_MLCC_CAP
J 0
(456 -838);
DISPLAY 0.638298 (456 -838);
PAINT BROWN (456 -838);
DISPLAY BOTH (456 -838);
FORCEPROP 1 LAST LOCATION C8T6
J 0
(450 -350);
DISPLAY 0.617021 (450 -350);
PAINT AQUA (450 -350);
FORCEPROP 1 LAST TOLERANCE 20%
J 0
(450 -500);
DISPLAY 0.617021 (450 -500);
PAINT SKYBLUE (450 -500);
FORCEPROP 1 LAST MATERIAL X5R
J 0
(450 -550);
DISPLAY 0.617021 (450 -550);
PAINT SKYBLUE (450 -550);
FORCEPROP 1 LASTPIN (400 -550) $PN 2
J 0
(410 -570);
DISPLAY 0.617021 (410 -570);
PAINT ORANGE (410 -570);
FORCEPROP 1 LASTPIN (400 -350) $PN 1
J 0
(410 -370);
DISPLAY 0.617021 (410 -370);
PAINT ORANGE (410 -370);
FORCEPROP 1 LAST PACK_TYPE 0603V
J 0
(450 -650);
DISPLAY 0.617021 (450 -650);
PAINT SKYBLUE (450 -650);
FORCEPROP 1 LAST VALUE 47UF
J 0
(450 -400);
DISPLAY 0.617021 (450 -400);
PAINT SKYBLUE (450 -400);
FORCEPROP 1 LAST PART_NUMBER 602433-106
J 0
(450 -600);
DISPLAY 0.617021 (450 -600);
PAINT BLUE (450 -600);
FORCEPROP 1 LAST VOLTAGE 4V
J 0
(450 -450);
DISPLAY 0.617021 (450 -450);
PAINT SKYBLUE (450 -450);
FORCEPROP 0 LAST BOM_SS E15431-004
J 0
(410 -797);
DISPLAY 0.510638 (410 -797);
PAINT BROWN (410 -797);
DISPLAY BOTH (410 -797);
FORCEPROP 1 LAST PATH I299
J 0
(450 -300);
DISPLAY 0.978723 (450 -300);
PAINT WHITE (450 -300);
DISPLAY INVISIBLE (450 -300);
FORCEPROP 2 LAST CDS_LIB dev_discrete
J 0
(400 -450);
PAINT ORANGE (400 -450);
DISPLAY INVISIBLE (400 -450);
FORCEPROP 2 LAST SEC 1
J 0
(450 -250);
DISPLAY 0.680851 (450 -250);
PAINT MONO (450 -250);
DISPLAY INVISIBLE (450 -250);
FORCEPROP 2 LAST SEC_TYPE 0603V
J 0
(450 -250);
DISPLAY 1.021277 (450 -250);
PAINT ORANGE (450 -250);
DISPLAY INVISIBLE (450 -250);
FORCEPROP 2 LAST CDS_SEC 1
J 0
(450 -300);
PAINT ORANGE (450 -300);
DISPLAY INVISIBLE (450 -300);
FORCEPROP 2 LAST CDS_LOCATION C8T6
J 0
(450 -350);
DISPLAY 0.617021 (450 -350);
PAINT AQUA (450 -350);
DISPLAY INVISIBLE (450 -350);
FORCEADD CAP_A..1
(700 -450);
FORCEPROP 0 LAST GROUP PWR_MLCC_CAP
J 0
(756 -688);
DISPLAY 0.638298 (756 -688);
PAINT BROWN (756 -688);
DISPLAY BOTH (756 -688);
FORCEPROP 1 LAST LOCATION C8T7
J 0
(750 -350);
DISPLAY 0.617021 (750 -350);
PAINT AQUA (750 -350);
FORCEPROP 1 LAST VOLTAGE 4V
J 0
(750 -450);
DISPLAY 0.617021 (750 -450);
PAINT SKYBLUE (750 -450);
FORCEPROP 1 LAST PART_NUMBER 602433-106
J 0
(750 -600);
DISPLAY 0.617021 (750 -600);
PAINT BLUE (750 -600);
FORCEPROP 1 LAST VALUE 47UF
J 0
(750 -400);
DISPLAY 0.617021 (750 -400);
PAINT SKYBLUE (750 -400);
FORCEPROP 1 LAST PACK_TYPE 0603V
J 0
(750 -650);
DISPLAY 0.617021 (750 -650);
PAINT SKYBLUE (750 -650);
FORCEPROP 1 LASTPIN (700 -550) $PN 2
J 0
(710 -570);
DISPLAY 0.617021 (710 -570);
PAINT ORANGE (710 -570);
FORCEPROP 1 LAST MATERIAL X5R
J 0
(750 -550);
DISPLAY 0.617021 (750 -550);
PAINT SKYBLUE (750 -550);
FORCEPROP 1 LASTPIN (700 -350) $PN 1
J 0
(710 -370);
DISPLAY 0.617021 (710 -370);
PAINT ORANGE (710 -370);
FORCEPROP 1 LAST TOLERANCE 20%
J 0
(750 -500);
DISPLAY 0.617021 (750 -500);
PAINT SKYBLUE (750 -500);
FORCEPROP 0 LAST BOM_SS E15431-004
J 0
(696 -759);
DISPLAY 0.510638 (696 -759);
PAINT BROWN (696 -759);
DISPLAY BOTH (696 -759);
FORCEPROP 1 LAST PATH I300
J 0
(750 -300);
DISPLAY 0.978723 (750 -300);
PAINT WHITE (750 -300);
DISPLAY INVISIBLE (750 -300);
FORCEPROP 2 LAST CDS_SEC 1
J 0
(750 -300);
PAINT ORANGE (750 -300);
DISPLAY INVISIBLE (750 -300);
FORCEPROP 2 LAST SEC_TYPE 0603V
J 0
(750 -250);
DISPLAY 1.021277 (750 -250);
PAINT ORANGE (750 -250);
DISPLAY INVISIBLE (750 -250);
FORCEPROP 2 LAST SEC 1
J 0
(750 -250);
DISPLAY 0.680851 (750 -250);
PAINT MONO (750 -250);
DISPLAY INVISIBLE (750 -250);
FORCEPROP 2 LAST CDS_LIB dev_discrete
J 0
(700 -450);
PAINT ORANGE (700 -450);
DISPLAY INVISIBLE (700 -450);
FORCEPROP 2 LAST CDS_LOCATION C8T7
J 0
(750 -350);
DISPLAY 0.617021 (750 -350);
PAINT AQUA (750 -350);
DISPLAY INVISIBLE (750 -350);
FORCEADD CAP_A..1
(975 -450);
FORCEPROP 0 LAST GROUP PWR_MLCC_CAP
J 0
(1031 -838);
DISPLAY 0.638298 (1031 -838);
PAINT BROWN (1031 -838);
DISPLAY BOTH (1031 -838);
FORCEPROP 1 LAST LOCATION C8T8
J 0
(1025 -350);
DISPLAY 0.617021 (1025 -350);
PAINT AQUA (1025 -350);
FORCEPROP 1 LAST TOLERANCE 20%
J 0
(1025 -500);
DISPLAY 0.617021 (1025 -500);
PAINT SKYBLUE (1025 -500);
FORCEPROP 1 LAST MATERIAL X5R
J 0
(1025 -550);
DISPLAY 0.617021 (1025 -550);
PAINT SKYBLUE (1025 -550);
FORCEPROP 1 LASTPIN (975 -550) $PN 2
J 0
(985 -570);
DISPLAY 0.617021 (985 -570);
PAINT ORANGE (985 -570);
FORCEPROP 1 LASTPIN (975 -350) $PN 1
J 0
(985 -370);
DISPLAY 0.617021 (985 -370);
PAINT ORANGE (985 -370);
FORCEPROP 1 LAST PACK_TYPE 0603V
J 0
(1025 -650);
DISPLAY 0.617021 (1025 -650);
PAINT SKYBLUE (1025 -650);
FORCEPROP 1 LAST VALUE 47UF
J 0
(1025 -400);
DISPLAY 0.617021 (1025 -400);
PAINT SKYBLUE (1025 -400);
FORCEPROP 1 LAST PART_NUMBER 602433-106
J 0
(1025 -600);
DISPLAY 0.617021 (1025 -600);
PAINT BLUE (1025 -600);
FORCEPROP 1 LAST VOLTAGE 4V
J 0
(1025 -450);
DISPLAY 0.617021 (1025 -450);
PAINT SKYBLUE (1025 -450);
FORCEPROP 0 LAST BOM_SS E15431-004
J 0
(982 -806);
DISPLAY 0.510638 (982 -806);
PAINT BROWN (982 -806);
DISPLAY BOTH (982 -806);
FORCEPROP 1 LAST PATH I301
J 0
(1025 -300);
DISPLAY 0.978723 (1025 -300);
PAINT WHITE (1025 -300);
DISPLAY INVISIBLE (1025 -300);
FORCEPROP 2 LAST CDS_LIB dev_discrete
J 0
(975 -450);
PAINT ORANGE (975 -450);
DISPLAY INVISIBLE (975 -450);
FORCEPROP 2 LAST SEC 1
J 0
(1025 -250);
DISPLAY 0.680851 (1025 -250);
PAINT MONO (1025 -250);
DISPLAY INVISIBLE (1025 -250);
FORCEPROP 2 LAST SEC_TYPE 0603V
J 0
(1025 -250);
DISPLAY 1.021277 (1025 -250);
PAINT ORANGE (1025 -250);
DISPLAY INVISIBLE (1025 -250);
FORCEPROP 2 LAST CDS_SEC 1
J 0
(1025 -300);
PAINT ORANGE (1025 -300);
DISPLAY INVISIBLE (1025 -300);
FORCEPROP 2 LAST CDS_LOCATION C8T8
J 0
(1025 -350);
DISPLAY 0.617021 (1025 -350);
PAINT AQUA (1025 -350);
DISPLAY INVISIBLE (1025 -350);
FORCEADD CAP_A..1
(1250 -450);
FORCEPROP 1 LAST VOLTAGE 4V
J 0
(1300 -450);
DISPLAY 0.617021 (1300 -450);
PAINT SKYBLUE (1300 -450);
FORCEPROP 1 LAST PART_NUMBER 602433-106
J 0
(1300 -600);
DISPLAY 0.617021 (1300 -600);
PAINT BLUE (1300 -600);
FORCEPROP 1 LAST VALUE 47UF
J 0
(1300 -400);
DISPLAY 0.617021 (1300 -400);
PAINT SKYBLUE (1300 -400);
FORCEPROP 1 LAST PACK_TYPE 0603V
J 0
(1300 -650);
DISPLAY 0.617021 (1300 -650);
PAINT SKYBLUE (1300 -650);
FORCEPROP 1 LASTPIN (1250 -350) $PN 1
J 0
(1260 -370);
DISPLAY 0.617021 (1260 -370);
PAINT ORANGE (1260 -370);
FORCEPROP 1 LASTPIN (1250 -550) $PN 2
J 0
(1260 -570);
DISPLAY 0.617021 (1260 -570);
PAINT ORANGE (1260 -570);
FORCEPROP 1 LAST MATERIAL X5R
J 0
(1300 -550);
DISPLAY 0.617021 (1300 -550);
PAINT SKYBLUE (1300 -550);
FORCEPROP 1 LAST TOLERANCE 20%
J 0
(1300 -500);
DISPLAY 0.617021 (1300 -500);
PAINT SKYBLUE (1300 -500);
FORCEPROP 1 LAST LOCATION C8U5
J 0
(1300 -350);
DISPLAY 0.617021 (1300 -350);
PAINT AQUA (1300 -350);
FORCEPROP 0 LAST GROUP PWR_MLCC_CAP
J 0
(1306 -688);
DISPLAY 0.638298 (1306 -688);
PAINT BROWN (1306 -688);
DISPLAY BOTH (1306 -688);
FORCEPROP 0 LAST BOM_SS E15431-004
J 0
(1282 -740);
DISPLAY 0.510638 (1282 -740);
PAINT BROWN (1282 -740);
DISPLAY BOTH (1282 -740);
FORCEPROP 1 LAST PATH I302
J 0
(1300 -300);
DISPLAY 0.978723 (1300 -300);
PAINT WHITE (1300 -300);
DISPLAY INVISIBLE (1300 -300);
FORCEPROP 2 LAST CDS_SEC 1
J 0
(1300 -300);
PAINT ORANGE (1300 -300);
DISPLAY INVISIBLE (1300 -300);
FORCEPROP 2 LAST SEC_TYPE 0603V
J 0
(1300 -250);
DISPLAY 1.021277 (1300 -250);
PAINT ORANGE (1300 -250);
DISPLAY INVISIBLE (1300 -250);
FORCEPROP 2 LAST SEC 1
J 0
(1300 -250);
DISPLAY 0.680851 (1300 -250);
PAINT MONO (1300 -250);
DISPLAY INVISIBLE (1300 -250);
FORCEPROP 2 LAST CDS_LIB dev_discrete
J 0
(1250 -450);
PAINT ORANGE (1250 -450);
DISPLAY INVISIBLE (1250 -450);
FORCEPROP 2 LAST CDS_LOCATION C8U5
J 0
(1300 -350);
DISPLAY 0.617021 (1300 -350);
PAINT AQUA (1300 -350);
DISPLAY INVISIBLE (1300 -350);
FORCEADD CAP_A..1
(1550 -450);
FORCEPROP 0 LAST GROUP PWR_MLCC_CAP
J 0
(1606 -838);
DISPLAY 0.638298 (1606 -838);
PAINT BROWN (1606 -838);
DISPLAY BOTH (1606 -838);
FORCEPROP 1 LAST LOCATION C8T9
J 0
(1600 -350);
DISPLAY 0.617021 (1600 -350);
PAINT AQUA (1600 -350);
FORCEPROP 1 LASTPIN (1550 -550) $PN 2
J 0
(1560 -570);
DISPLAY 0.617021 (1560 -570);
PAINT ORANGE (1560 -570);
FORCEPROP 1 LASTPIN (1550 -350) $PN 1
J 0
(1560 -370);
DISPLAY 0.617021 (1560 -370);
PAINT ORANGE (1560 -370);
FORCEPROP 1 LAST VALUE 47UF
J 0
(1600 -400);
DISPLAY 0.617021 (1600 -400);
PAINT SKYBLUE (1600 -400);
FORCEPROP 1 LAST VOLTAGE 4V
J 0
(1600 -450);
DISPLAY 0.617021 (1600 -450);
PAINT SKYBLUE (1600 -450);
FORCEPROP 1 LAST PACK_TYPE 0603V
J 0
(1600 -650);
DISPLAY 0.617021 (1600 -650);
PAINT SKYBLUE (1600 -650);
FORCEPROP 1 LAST PART_NUMBER 602433-106
J 0
(1600 -600);
DISPLAY 0.617021 (1600 -600);
PAINT BLUE (1600 -600);
FORCEPROP 1 LAST MATERIAL X5R
J 0
(1600 -550);
DISPLAY 0.617021 (1600 -550);
PAINT SKYBLUE (1600 -550);
FORCEPROP 1 LAST TOLERANCE 20%
J 0
(1600 -500);
DISPLAY 0.617021 (1600 -500);
PAINT SKYBLUE (1600 -500);
FORCEPROP 0 LAST BOM_SS E15431-004
J 0
(1558 -795);
DISPLAY 0.510638 (1558 -795);
PAINT BROWN (1558 -795);
DISPLAY BOTH (1558 -795);
FORCEPROP 1 LAST PATH I303
J 0
(1600 -300);
DISPLAY 0.978723 (1600 -300);
PAINT WHITE (1600 -300);
DISPLAY INVISIBLE (1600 -300);
FORCEPROP 2 LAST CDS_LIB dev_discrete
J 0
(1550 -450);
PAINT ORANGE (1550 -450);
DISPLAY INVISIBLE (1550 -450);
FORCEPROP 2 LAST SEC 1
J 0
(1600 -250);
DISPLAY 0.680851 (1600 -250);
PAINT MONO (1600 -250);
DISPLAY INVISIBLE (1600 -250);
FORCEPROP 2 LAST SEC_TYPE 0603V
J 0
(1600 -250);
DISPLAY 1.021277 (1600 -250);
PAINT ORANGE (1600 -250);
DISPLAY INVISIBLE (1600 -250);
FORCEPROP 2 LAST CDS_SEC 1
J 0
(1600 -300);
PAINT ORANGE (1600 -300);
DISPLAY INVISIBLE (1600 -300);
FORCEPROP 2 LAST CDS_LOCATION C8T9
J 0
(1600 -350);
DISPLAY 0.617021 (1600 -350);
PAINT AQUA (1600 -350);
DISPLAY INVISIBLE (1600 -350);
FORCEADD CAP_A..1
(1850 -450);
FORCEPROP 1 LAST LOCATION C8T10
J 0
(1900 -350);
DISPLAY 0.617021 (1900 -350);
PAINT AQUA (1900 -350);
FORCEPROP 1 LAST VOLTAGE 4V
J 0
(1900 -450);
DISPLAY 0.617021 (1900 -450);
PAINT SKYBLUE (1900 -450);
FORCEPROP 1 LAST VALUE 47UF
J 0
(1900 -400);
DISPLAY 0.617021 (1900 -400);
PAINT SKYBLUE (1900 -400);
FORCEPROP 1 LASTPIN (1850 -350) $PN 1
J 0
(1860 -370);
DISPLAY 0.617021 (1860 -370);
PAINT ORANGE (1860 -370);
FORCEPROP 1 LASTPIN (1850 -550) $PN 2
J 0
(1860 -570);
DISPLAY 0.617021 (1860 -570);
PAINT ORANGE (1860 -570);
FORCEPROP 1 LAST MATERIAL X5R
J 0
(1900 -550);
DISPLAY 0.617021 (1900 -550);
PAINT SKYBLUE (1900 -550);
FORCEPROP 1 LAST TOLERANCE 20%
J 0
(1900 -500);
DISPLAY 0.617021 (1900 -500);
PAINT SKYBLUE (1900 -500);
FORCEPROP 1 LAST PART_NUMBER 602433-106
J 0
(1900 -600);
DISPLAY 0.617021 (1900 -600);
PAINT BLUE (1900 -600);
FORCEPROP 1 LAST PACK_TYPE 0603V
J 0
(1900 -650);
DISPLAY 0.617021 (1900 -650);
PAINT SKYBLUE (1900 -650);
FORCEPROP 0 LAST BOM_SS E15431-004
J 0
(1844 -749);
DISPLAY 0.510638 (1844 -749);
PAINT BROWN (1844 -749);
DISPLAY BOTH (1844 -749);
FORCEPROP 0 LAST GROUP PWR_MLCC_CAP
J 0
(1906 -688);
DISPLAY 0.638298 (1906 -688);
PAINT BROWN (1906 -688);
DISPLAY BOTH (1906 -688);
FORCEPROP 1 LAST PATH I304
J 0
(1900 -300);
DISPLAY 0.978723 (1900 -300);
PAINT WHITE (1900 -300);
DISPLAY INVISIBLE (1900 -300);
FORCEPROP 2 LAST CDS_SEC 1
J 0
(1900 -300);
PAINT ORANGE (1900 -300);
DISPLAY INVISIBLE (1900 -300);
FORCEPROP 2 LAST SEC_TYPE 0603V
J 0
(1900 -250);
DISPLAY 1.021277 (1900 -250);
PAINT ORANGE (1900 -250);
DISPLAY INVISIBLE (1900 -250);
FORCEPROP 2 LAST SEC 1
J 0
(1900 -250);
DISPLAY 0.680851 (1900 -250);
PAINT MONO (1900 -250);
DISPLAY INVISIBLE (1900 -250);
FORCEPROP 2 LAST CDS_LIB dev_discrete
J 0
(1850 -450);
PAINT ORANGE (1850 -450);
DISPLAY INVISIBLE (1850 -450);
FORCEPROP 2 LAST CDS_LOCATION C8T10
J 0
(1900 -350);
DISPLAY 0.617021 (1900 -350);
PAINT AQUA (1900 -350);
DISPLAY INVISIBLE (1900 -350);
FORCEADD CAP_A..1
(2125 -450);
FORCEPROP 0 LAST GROUP PWR_MLCC_CAP
J 0
(2181 -838);
DISPLAY 0.638298 (2181 -838);
PAINT BROWN (2181 -838);
DISPLAY BOTH (2181 -838);
FORCEPROP 1 LAST VOLTAGE 4V
J 0
(2175 -450);
DISPLAY 0.617021 (2175 -450);
PAINT SKYBLUE (2175 -450);
FORCEPROP 1 LAST VALUE 47UF
J 0
(2175 -400);
DISPLAY 0.617021 (2175 -400);
PAINT SKYBLUE (2175 -400);
FORCEPROP 1 LASTPIN (2125 -550) $PN 2
J 0
(2135 -570);
DISPLAY 0.617021 (2135 -570);
PAINT ORANGE (2135 -570);
FORCEPROP 1 LAST MATERIAL X5R
J 0
(2175 -550);
DISPLAY 0.617021 (2175 -550);
PAINT SKYBLUE (2175 -550);
FORCEPROP 1 LAST TOLERANCE 20%
J 0
(2175 -500);
DISPLAY 0.617021 (2175 -500);
PAINT SKYBLUE (2175 -500);
FORCEPROP 1 LASTPIN (2125 -350) $PN 1
J 0
(2135 -370);
DISPLAY 0.617021 (2135 -370);
PAINT ORANGE (2135 -370);
FORCEPROP 1 LAST LOCATION C8U4
J 0
(2175 -350);
DISPLAY 0.617021 (2175 -350);
PAINT AQUA (2175 -350);
FORCEPROP 1 LAST PART_NUMBER 602433-106
J 0
(2175 -600);
DISPLAY 0.617021 (2175 -600);
PAINT BLUE (2175 -600);
FORCEPROP 1 LAST PACK_TYPE 0603V
J 0
(2175 -650);
DISPLAY 0.617021 (2175 -650);
PAINT SKYBLUE (2175 -650);
FORCEPROP 0 LAST BOM_SS E15431-004
J 0
(2133 -792);
DISPLAY 0.510638 (2133 -792);
PAINT BROWN (2133 -792);
DISPLAY BOTH (2133 -792);
FORCEPROP 2 LAST CDS_SEC 1
J 0
(2175 -300);
PAINT ORANGE (2175 -300);
DISPLAY INVISIBLE (2175 -300);
FORCEPROP 2 LAST SEC_TYPE 0603V
J 0
(2175 -250);
DISPLAY 1.021277 (2175 -250);
PAINT ORANGE (2175 -250);
DISPLAY INVISIBLE (2175 -250);
FORCEPROP 2 LAST SEC 1
J 0
(2175 -250);
DISPLAY 0.680851 (2175 -250);
PAINT MONO (2175 -250);
DISPLAY INVISIBLE (2175 -250);
FORCEPROP 2 LAST CDS_LIB dev_discrete
J 0
(2125 -450);
PAINT ORANGE (2125 -450);
DISPLAY INVISIBLE (2125 -450);
FORCEPROP 1 LAST PATH I305
J 0
(2175 -300);
DISPLAY 0.978723 (2175 -300);
PAINT WHITE (2175 -300);
DISPLAY INVISIBLE (2175 -300);
FORCEPROP 2 LAST CDS_LOCATION C8U4
J 0
(2175 -350);
DISPLAY 0.617021 (2175 -350);
PAINT AQUA (2175 -350);
DISPLAY INVISIBLE (2175 -350);
FORCEADD CAP..1
(3850 2825);
FORCEPROP 1 LAST VALUE 100UF
J 0
(3900 2875);
DISPLAY 0.617021 (3900 2875);
PAINT SKYBLUE (3900 2875);
FORCEPROP 1 LAST VOLTAGE 4V
J 0
(3900 2825);
DISPLAY 0.617021 (3900 2825);
PAINT SKYBLUE (3900 2825);
FORCEPROP 1 LASTPIN (3850 2725) $PN 2
J 0
(3860 2705);
DISPLAY 0.617021 (3860 2705);
PAINT ORANGE (3860 2705);
FORCEPROP 1 LASTPIN (3850 2925) $PN 1
J 0
(3860 2905);
DISPLAY 0.617021 (3860 2905);
PAINT ORANGE (3860 2905);
FORCEPROP 1 LAST LOCATION C8U11
J 0
(3900 2925);
DISPLAY 0.617021 (3900 2925);
PAINT AQUA (3900 2925);
FORCEPROP 1 LAST PACK_TYPE 0805
J 0
(3900 2675);
DISPLAY 0.617021 (3900 2675);
PAINT SKYBLUE (3900 2675);
FORCEPROP 1 LAST TOLERANCE 20%
J 0
(3900 2775);
DISPLAY 0.617021 (3900 2775);
PAINT SKYBLUE (3900 2775);
FORCEPROP 0 LAST NEW_MATERIAL X6S
J 0
(3900 2575);
DISPLAY 0.638298 (3900 2575);
PAINT BROWN (3900 2575);
DISPLAY BOTH (3900 2575);
FORCEPROP 0 LAST GROUP PWR_MLCC_CAP
J 0
(3906 2462);
DISPLAY 0.638298 (3906 2462);
PAINT BROWN (3906 2462);
DISPLAY BOTH (3906 2462);
FORCEPROP 1 LAST PART_NUMBER 602433-112
J 0
(3900 2725);
DISPLAY 0.617021 (3900 2725);
PAINT BLUE (3900 2725);
FORCEPROP 0 LAST BOM_SS NOPOP
J 0
(3888 2518);
DISPLAY 0.638298 (3888 2518);
PAINT BROWN (3888 2518);
DISPLAY BOTH (3888 2518);
FORCEPROP 0 LAST NEW_PN 078.1071T.M002
J 0
(3909 2623);
DISPLAY 0.638298 (3909 2623);
PAINT BROWN (3909 2623);
DISPLAY BOTH (3909 2623);
FORCEPROP 1 LAST PATH I307
J 0
(3900 2975);
DISPLAY 0.978723 (3900 2975);
PAINT WHITE (3900 2975);
DISPLAY INVISIBLE (3900 2975);
FORCEPROP 1 LAST MATERIAL X5R
J 0
(3900 2725);
DISPLAY 0.617021 (3900 2725);
PAINT SKYBLUE (3900 2725);
DISPLAY INVISIBLE (3900 2725);
FORCEPROP 2 LAST SEC 1
J 0
(3900 3025);
DISPLAY 0.680851 (3900 3025);
PAINT MONO (3900 3025);
DISPLAY INVISIBLE (3900 3025);
FORCEPROP 2 LAST SEC_TYPE 0805
J 0
(3900 3025);
DISPLAY 1.021277 (3900 3025);
PAINT ORANGE (3900 3025);
DISPLAY INVISIBLE (3900 3025);
FORCEPROP 2 LAST ROOM VDDQ_ABC_PWR_VR
J 0
(3900 2975);
PAINT MONO (3900 2975);
DISPLAY INVISIBLE (3900 2975);
FORCEPROP 2 LAST BOM_COST MEM_VRD_PVDDQ_CD
J 0
(3900 2975);
PAINT MONO (3900 2975);
DISPLAY INVISIBLE (3900 2975);
FORCEPROP 2 LAST CDS_LIB mstr_discrete
J 0
(3850 2825);
PAINT MONO (3850 2825);
DISPLAY INVISIBLE (3850 2825);
FORCEPROP 0 LAST CDS_SEC 1
J 0
(3900 2975);
PAINT MONO (3900 2975);
DISPLAY INVISIBLE (3900 2975);
FORCEPROP 2 LAST CDS_LOCATION C8U11
J 0
(3900 2925);
DISPLAY 0.617021 (3900 2925);
PAINT AQUA (3900 2925);
DISPLAY INVISIBLE (3900 2925);
FORCEADD CAP..1
(3150 2825);
FORCEPROP 1 LAST LOCATION C7U7
J 0
(3200 2925);
DISPLAY 0.617021 (3200 2925);
PAINT AQUA (3200 2925);
FORCEPROP 1 LASTPIN (3150 2925) $PN 1
J 0
(3160 2905);
DISPLAY 0.617021 (3160 2905);
PAINT ORANGE (3160 2905);
FORCEPROP 0 LAST NEW_MATERIAL X6S
J 0
(3200 2575);
DISPLAY 0.638298 (3200 2575);
PAINT BROWN (3200 2575);
DISPLAY BOTH (3200 2575);
FORCEPROP 0 LAST GROUP PWR_MLCC_CAP
J 0
(3206 2462);
DISPLAY 0.638298 (3206 2462);
PAINT BROWN (3206 2462);
DISPLAY BOTH (3206 2462);
FORCEPROP 1 LAST VOLTAGE 4V
J 0
(3200 2825);
DISPLAY 0.617021 (3200 2825);
PAINT SKYBLUE (3200 2825);
FORCEPROP 1 LAST TOLERANCE 20%
J 0
(3200 2775);
DISPLAY 0.617021 (3200 2775);
PAINT SKYBLUE (3200 2775);
FORCEPROP 0 LAST BOM_SS NOPOP
J 0
(3188 2518);
DISPLAY 0.638298 (3188 2518);
PAINT BROWN (3188 2518);
DISPLAY BOTH (3188 2518);
FORCEPROP 1 LAST PART_NUMBER 602433-112
J 0
(3200 2725);
DISPLAY 0.617021 (3200 2725);
PAINT BLUE (3200 2725);
FORCEPROP 1 LAST PACK_TYPE 0805
J 0
(3200 2675);
DISPLAY 0.617021 (3200 2675);
PAINT SKYBLUE (3200 2675);
FORCEPROP 1 LASTPIN (3150 2725) $PN 2
J 0
(3160 2705);
DISPLAY 0.617021 (3160 2705);
PAINT ORANGE (3160 2705);
FORCEPROP 1 LAST VALUE 100UF
J 0
(3200 2875);
DISPLAY 0.617021 (3200 2875);
PAINT SKYBLUE (3200 2875);
FORCEPROP 0 LAST NEW_PN 078.1071T.M002
J 0
(3209 2623);
DISPLAY 0.638298 (3209 2623);
PAINT BROWN (3209 2623);
DISPLAY BOTH (3209 2623);
FORCEPROP 1 LAST PATH I308
J 0
(3200 2975);
DISPLAY 0.978723 (3200 2975);
PAINT WHITE (3200 2975);
DISPLAY INVISIBLE (3200 2975);
FORCEPROP 0 LAST CDS_SEC 1
J 0
(3200 2975);
PAINT MONO (3200 2975);
DISPLAY INVISIBLE (3200 2975);
FORCEPROP 2 LAST CDS_LIB mstr_discrete
J 0
(3150 2825);
PAINT MONO (3150 2825);
DISPLAY INVISIBLE (3150 2825);
FORCEPROP 2 LAST BOM_COST MEM_VRD_PVDDQ_CD
J 0
(3200 2975);
PAINT MONO (3200 2975);
DISPLAY INVISIBLE (3200 2975);
FORCEPROP 2 LAST ROOM VDDQ_ABC_PWR_VR
J 0
(3200 2975);
PAINT MONO (3200 2975);
DISPLAY INVISIBLE (3200 2975);
FORCEPROP 2 LAST SEC_TYPE 0805
J 0
(3200 3025);
DISPLAY 1.021277 (3200 3025);
PAINT ORANGE (3200 3025);
DISPLAY INVISIBLE (3200 3025);
FORCEPROP 2 LAST SEC 1
J 0
(3200 3025);
DISPLAY 0.680851 (3200 3025);
PAINT MONO (3200 3025);
DISPLAY INVISIBLE (3200 3025);
FORCEPROP 1 LAST MATERIAL X5R
J 0
(3200 2725);
DISPLAY 0.617021 (3200 2725);
PAINT SKYBLUE (3200 2725);
DISPLAY INVISIBLE (3200 2725);
FORCEPROP 2 LAST CDS_LOCATION C7U7
J 0
(3200 2925);
DISPLAY 0.617021 (3200 2925);
PAINT AQUA (3200 2925);
DISPLAY INVISIBLE (3200 2925);
FORCEADD CAP..1
(3500 2825);
FORCEPROP 0 LAST NEW_MATERIAL X6S
J 0
(3550 2350);
DISPLAY 0.638298 (3550 2350);
PAINT BROWN (3550 2350);
DISPLAY BOTH (3550 2350);
FORCEPROP 0 LAST BOM_SS NOPOP
J 0
(3538 2293);
DISPLAY 0.638298 (3538 2293);
PAINT BROWN (3538 2293);
DISPLAY BOTH (3538 2293);
FORCEPROP 1 LAST VALUE 100UF
J 0
(3550 2875);
DISPLAY 0.617021 (3550 2875);
PAINT SKYBLUE (3550 2875);
FORCEPROP 1 LAST LOCATION C7T1
J 0
(3550 2925);
DISPLAY 0.617021 (3550 2925);
PAINT AQUA (3550 2925);
FORCEPROP 1 LASTPIN (3500 2925) $PN 1
J 0
(3510 2905);
DISPLAY 0.617021 (3510 2905);
PAINT ORANGE (3510 2905);
FORCEPROP 1 LAST PACK_TYPE 0805
J 0
(3550 2675);
DISPLAY 0.617021 (3550 2675);
PAINT SKYBLUE (3550 2675);
FORCEPROP 0 LAST GROUP PWR_MLCC_CAP
J 0
(3556 2237);
DISPLAY 0.638298 (3556 2237);
PAINT BROWN (3556 2237);
DISPLAY BOTH (3556 2237);
FORCEPROP 1 LASTPIN (3500 2725) $PN 2
J 0
(3510 2705);
DISPLAY 0.617021 (3510 2705);
PAINT ORANGE (3510 2705);
FORCEPROP 1 LAST TOLERANCE 20%
J 0
(3550 2775);
DISPLAY 0.617021 (3550 2775);
PAINT SKYBLUE (3550 2775);
FORCEPROP 1 LAST VOLTAGE 4V
J 0
(3550 2825);
DISPLAY 0.617021 (3550 2825);
PAINT SKYBLUE (3550 2825);
FORCEPROP 1 LAST PART_NUMBER 602433-112
J 0
(3550 2725);
DISPLAY 0.617021 (3550 2725);
PAINT BLUE (3550 2725);
FORCEPROP 0 LAST NEW_PN 078.1071T.M002
J 0
(3559 2398);
DISPLAY 0.638298 (3559 2398);
PAINT BROWN (3559 2398);
DISPLAY BOTH (3559 2398);
FORCEPROP 1 LAST PATH I309
J 0
(3550 2975);
DISPLAY 0.978723 (3550 2975);
PAINT WHITE (3550 2975);
DISPLAY INVISIBLE (3550 2975);
FORCEPROP 1 LAST MATERIAL X5R
J 0
(3550 2725);
DISPLAY 0.617021 (3550 2725);
PAINT SKYBLUE (3550 2725);
DISPLAY INVISIBLE (3550 2725);
FORCEPROP 2 LAST SEC 1
J 0
(3550 3025);
DISPLAY 0.680851 (3550 3025);
PAINT MONO (3550 3025);
DISPLAY INVISIBLE (3550 3025);
FORCEPROP 2 LAST SEC_TYPE 0805
J 0
(3550 3025);
DISPLAY 1.021277 (3550 3025);
PAINT ORANGE (3550 3025);
DISPLAY INVISIBLE (3550 3025);
FORCEPROP 2 LAST ROOM VDDQ_ABC_PWR_VR
J 0
(3550 2975);
PAINT MONO (3550 2975);
DISPLAY INVISIBLE (3550 2975);
FORCEPROP 2 LAST BOM_COST MEM_VRD_PVDDQ_CD
J 0
(3550 2975);
PAINT MONO (3550 2975);
DISPLAY INVISIBLE (3550 2975);
FORCEPROP 2 LAST CDS_LIB mstr_discrete
J 0
(3500 2825);
PAINT MONO (3500 2825);
DISPLAY INVISIBLE (3500 2825);
FORCEPROP 0 LAST CDS_SEC 1
J 0
(3550 2975);
PAINT MONO (3550 2975);
DISPLAY INVISIBLE (3550 2975);
FORCEPROP 2 LAST CDS_LOCATION C7T1
J 0
(3550 2925);
DISPLAY 0.617021 (3550 2925);
PAINT AQUA (3550 2925);
DISPLAY INVISIBLE (3550 2925);
FORCEADD CAP..1
(4250 2825);
FORCEPROP 0 LAST BOM_SS NOPOP
J 0
(4288 2293);
DISPLAY 0.638298 (4288 2293);
PAINT BROWN (4288 2293);
DISPLAY BOTH (4288 2293);
FORCEPROP 0 LAST NEW_MATERIAL X6S
J 0
(4300 2350);
DISPLAY 0.638298 (4300 2350);
PAINT BROWN (4300 2350);
DISPLAY BOTH (4300 2350);
FORCEPROP 1 LAST PACK_TYPE 0805
J 0
(4300 2675);
DISPLAY 0.617021 (4300 2675);
PAINT SKYBLUE (4300 2675);
FORCEPROP 1 LAST PART_NUMBER 602433-112
J 0
(4300 2725);
DISPLAY 0.617021 (4300 2725);
PAINT BLUE (4300 2725);
FORCEPROP 1 LAST VALUE 100UF
J 0
(4300 2875);
DISPLAY 0.617021 (4300 2875);
PAINT SKYBLUE (4300 2875);
FORCEPROP 1 LAST VOLTAGE 4V
J 0
(4300 2825);
DISPLAY 0.617021 (4300 2825);
PAINT SKYBLUE (4300 2825);
FORCEPROP 1 LAST TOLERANCE 20%
J 0
(4300 2775);
DISPLAY 0.617021 (4300 2775);
PAINT SKYBLUE (4300 2775);
FORCEPROP 1 LASTPIN (4250 2725) $PN 2
J 0
(4260 2705);
DISPLAY 0.617021 (4260 2705);
PAINT ORANGE (4260 2705);
FORCEPROP 1 LASTPIN (4250 2925) $PN 1
J 0
(4260 2905);
DISPLAY 0.617021 (4260 2905);
PAINT ORANGE (4260 2905);
FORCEPROP 1 LAST LOCATION C8U12
J 0
(4300 2925);
DISPLAY 0.617021 (4300 2925);
PAINT AQUA (4300 2925);
FORCEPROP 0 LAST GROUP PWR_MLCC_CAP
J 0
(4306 2262);
DISPLAY 0.638298 (4306 2262);
PAINT BROWN (4306 2262);
DISPLAY BOTH (4306 2262);
FORCEPROP 0 LAST NEW_PN 078.1071T.M002
J 0
(4309 2398);
DISPLAY 0.638298 (4309 2398);
PAINT BROWN (4309 2398);
DISPLAY BOTH (4309 2398);
FORCEPROP 1 LAST MATERIAL X5R
J 0
(4300 2725);
DISPLAY 0.617021 (4300 2725);
PAINT SKYBLUE (4300 2725);
DISPLAY INVISIBLE (4300 2725);
FORCEPROP 2 LAST SEC 1
J 0
(4300 3025);
DISPLAY 0.680851 (4300 3025);
PAINT MONO (4300 3025);
DISPLAY INVISIBLE (4300 3025);
FORCEPROP 2 LAST SEC_TYPE 0805
J 0
(4300 3025);
DISPLAY 1.021277 (4300 3025);
PAINT ORANGE (4300 3025);
DISPLAY INVISIBLE (4300 3025);
FORCEPROP 2 LAST ROOM VDDQ_ABC_PWR_VR
J 0
(4300 2975);
PAINT MONO (4300 2975);
DISPLAY INVISIBLE (4300 2975);
FORCEPROP 2 LAST BOM_COST MEM_VRD_PVDDQ_CD
J 0
(4300 2975);
PAINT MONO (4300 2975);
DISPLAY INVISIBLE (4300 2975);
FORCEPROP 2 LAST CDS_LIB mstr_discrete
J 0
(4250 2825);
PAINT MONO (4250 2825);
DISPLAY INVISIBLE (4250 2825);
FORCEPROP 0 LAST CDS_SEC 1
J 0
(4300 2975);
PAINT MONO (4300 2975);
DISPLAY INVISIBLE (4300 2975);
FORCEPROP 1 LAST PATH I310
J 0
(4300 2975);
DISPLAY 0.978723 (4300 2975);
PAINT WHITE (4300 2975);
DISPLAY INVISIBLE (4300 2975);
FORCEPROP 2 LAST CDS_LOCATION C8U12
J 0
(4300 2925);
DISPLAY 0.617021 (4300 2925);
PAINT AQUA (4300 2925);
DISPLAY INVISIBLE (4300 2925);
FORCEADD CAP..1
(2400 2825);
FORCEPROP 0 LAST BOM_SS NOPOP
J 0
(2438 2518);
DISPLAY 0.638298 (2438 2518);
PAINT BROWN (2438 2518);
DISPLAY BOTH (2438 2518);
FORCEPROP 0 LAST NEW_MATERIAL X6S
J 0
(2450 2575);
DISPLAY 0.638298 (2450 2575);
PAINT BROWN (2450 2575);
DISPLAY BOTH (2450 2575);
FORCEPROP 1 LAST VALUE 100UF
J 0
(2450 2875);
DISPLAY 0.617021 (2450 2875);
PAINT SKYBLUE (2450 2875);
FORCEPROP 0 LAST GROUP PWR_MLCC_CAP
J 0
(2456 2487);
DISPLAY 0.638298 (2456 2487);
PAINT BROWN (2456 2487);
DISPLAY BOTH (2456 2487);
FORCEPROP 1 LAST PART_NUMBER 602433-112
J 0
(2450 2725);
DISPLAY 0.617021 (2450 2725);
PAINT BLUE (2450 2725);
FORCEPROP 1 LAST TOLERANCE 20%
J 0
(2450 2775);
DISPLAY 0.617021 (2450 2775);
PAINT SKYBLUE (2450 2775);
FORCEPROP 1 LAST PACK_TYPE 0805
J 0
(2450 2675);
DISPLAY 0.617021 (2450 2675);
PAINT SKYBLUE (2450 2675);
FORCEPROP 1 LAST VOLTAGE 4V
J 0
(2450 2825);
DISPLAY 0.617021 (2450 2825);
PAINT SKYBLUE (2450 2825);
FORCEPROP 1 LASTPIN (2400 2725) $PN 2
J 0
(2410 2705);
DISPLAY 0.617021 (2410 2705);
PAINT ORANGE (2410 2705);
FORCEPROP 1 LASTPIN (2400 2925) $PN 1
J 0
(2410 2905);
DISPLAY 0.617021 (2410 2905);
PAINT ORANGE (2410 2905);
FORCEPROP 1 LAST LOCATION C2G16
J 0
(2450 2925);
DISPLAY 0.617021 (2450 2925);
PAINT AQUA (2450 2925);
FORCEPROP 0 LAST NEW_PN 078.1071T.M002
J 0
(2459 2623);
DISPLAY 0.638298 (2459 2623);
PAINT BROWN (2459 2623);
DISPLAY BOTH (2459 2623);
FORCEPROP 1 LAST MATERIAL X5R
J 0
(2450 2725);
DISPLAY 0.617021 (2450 2725);
PAINT SKYBLUE (2450 2725);
DISPLAY INVISIBLE (2450 2725);
FORCEPROP 2 LAST SEC 1
J 0
(2450 3025);
DISPLAY 0.680851 (2450 3025);
PAINT MONO (2450 3025);
DISPLAY INVISIBLE (2450 3025);
FORCEPROP 2 LAST SEC_TYPE 0805
J 0
(2450 3025);
DISPLAY 1.021277 (2450 3025);
PAINT ORANGE (2450 3025);
DISPLAY INVISIBLE (2450 3025);
FORCEPROP 2 LAST ROOM VDDQ_ABC_PWR_VR
J 0
(2450 2975);
PAINT MONO (2450 2975);
DISPLAY INVISIBLE (2450 2975);
FORCEPROP 2 LAST BOM_COST MEM_VRD_PVDDQ_CD
J 0
(2450 2975);
PAINT MONO (2450 2975);
DISPLAY INVISIBLE (2450 2975);
FORCEPROP 2 LAST CDS_LIB mstr_discrete
J 0
(2400 2825);
PAINT MONO (2400 2825);
DISPLAY INVISIBLE (2400 2825);
FORCEPROP 0 LAST CDS_SEC 1
J 0
(2450 2975);
PAINT MONO (2450 2975);
DISPLAY INVISIBLE (2450 2975);
FORCEPROP 1 LAST PATH I311
J 0
(2450 2975);
DISPLAY 0.978723 (2450 2975);
PAINT WHITE (2450 2975);
DISPLAY INVISIBLE (2450 2975);
FORCEPROP 2 LAST CDS_LOCATION C2G16
J 0
(2450 2925);
DISPLAY 0.617021 (2450 2925);
PAINT AQUA (2450 2925);
DISPLAY INVISIBLE (2450 2925);
FORCEADD CAP..1
(2750 2825);
FORCEPROP 1 LAST PART_NUMBER 602433-112
J 0
(2800 2725);
DISPLAY 0.617021 (2800 2725);
PAINT BLUE (2800 2725);
FORCEPROP 0 LAST BOM_SS NOPOP
J 0
(2788 2293);
DISPLAY 0.638298 (2788 2293);
PAINT BROWN (2788 2293);
DISPLAY BOTH (2788 2293);
FORCEPROP 1 LAST TOLERANCE 20%
J 0
(2800 2775);
DISPLAY 0.617021 (2800 2775);
PAINT SKYBLUE (2800 2775);
FORCEPROP 1 LAST VOLTAGE 4V
J 0
(2800 2825);
DISPLAY 0.617021 (2800 2825);
PAINT SKYBLUE (2800 2825);
FORCEPROP 1 LAST VALUE 100UF
J 0
(2800 2875);
DISPLAY 0.617021 (2800 2875);
PAINT SKYBLUE (2800 2875);
FORCEPROP 1 LAST LOCATION C2G7
J 0
(2800 2925);
DISPLAY 0.617021 (2800 2925);
PAINT AQUA (2800 2925);
FORCEPROP 0 LAST NEW_MATERIAL X6S
J 0
(2800 2350);
DISPLAY 0.638298 (2800 2350);
PAINT BROWN (2800 2350);
DISPLAY BOTH (2800 2350);
FORCEPROP 1 LAST PACK_TYPE 0805
J 0
(2800 2675);
DISPLAY 0.617021 (2800 2675);
PAINT SKYBLUE (2800 2675);
FORCEPROP 1 LASTPIN (2750 2725) $PN 2
J 0
(2760 2705);
DISPLAY 0.617021 (2760 2705);
PAINT ORANGE (2760 2705);
FORCEPROP 1 LASTPIN (2750 2925) $PN 1
J 0
(2760 2905);
DISPLAY 0.617021 (2760 2905);
PAINT ORANGE (2760 2905);
FORCEPROP 0 LAST GROUP PWR_MLCC_CAP
J 0
(2806 2262);
DISPLAY 0.638298 (2806 2262);
PAINT BROWN (2806 2262);
DISPLAY BOTH (2806 2262);
FORCEPROP 0 LAST NEW_PN 078.1071T.M002
J 0
(2809 2398);
DISPLAY 0.638298 (2809 2398);
PAINT BROWN (2809 2398);
DISPLAY BOTH (2809 2398);
FORCEPROP 1 LAST PATH I312
J 0
(2800 2975);
DISPLAY 0.978723 (2800 2975);
PAINT WHITE (2800 2975);
DISPLAY INVISIBLE (2800 2975);
FORCEPROP 1 LAST MATERIAL X5R
J 0
(2800 2725);
DISPLAY 0.617021 (2800 2725);
PAINT SKYBLUE (2800 2725);
DISPLAY INVISIBLE (2800 2725);
FORCEPROP 2 LAST SEC 1
J 0
(2800 3025);
DISPLAY 0.680851 (2800 3025);
PAINT MONO (2800 3025);
DISPLAY INVISIBLE (2800 3025);
FORCEPROP 2 LAST SEC_TYPE 0805
J 0
(2800 3025);
DISPLAY 1.021277 (2800 3025);
PAINT ORANGE (2800 3025);
DISPLAY INVISIBLE (2800 3025);
FORCEPROP 2 LAST ROOM VDDQ_ABC_PWR_VR
J 0
(2800 2975);
PAINT MONO (2800 2975);
DISPLAY INVISIBLE (2800 2975);
FORCEPROP 2 LAST BOM_COST MEM_VRD_PVDDQ_CD
J 0
(2800 2975);
PAINT MONO (2800 2975);
DISPLAY INVISIBLE (2800 2975);
FORCEPROP 2 LAST CDS_LIB mstr_discrete
J 0
(2750 2825);
PAINT MONO (2750 2825);
DISPLAY INVISIBLE (2750 2825);
FORCEPROP 0 LAST CDS_SEC 1
J 0
(2800 2975);
PAINT MONO (2800 2975);
DISPLAY INVISIBLE (2800 2975);
FORCEPROP 2 LAST CDS_LOCATION C2G7
J 0
(2800 2925);
DISPLAY 0.617021 (2800 2925);
PAINT AQUA (2800 2925);
DISPLAY INVISIBLE (2800 2925);
FORCEADD CAP..1
(-2325 3100);
FORCEPROP 1 LAST VALUE 100UF
J 0
(-2275 3150);
DISPLAY 0.617021 (-2275 3150);
PAINT SKYBLUE (-2275 3150);
FORCEPROP 1 LAST LOCATION C8P30
J 0
(-2275 3200);
DISPLAY 0.617021 (-2275 3200);
PAINT AQUA (-2275 3200);
FORCEPROP 1 LASTPIN (-2325 3200) $PN 1
J 0
(-2315 3180);
DISPLAY 0.617021 (-2315 3180);
PAINT ORANGE (-2315 3180);
FORCEPROP 1 LASTPIN (-2325 3000) $PN 2
J 0
(-2315 2980);
DISPLAY 0.617021 (-2315 2980);
PAINT ORANGE (-2315 2980);
FORCEPROP 1 LAST TOLERANCE 20%
J 0
(-2275 3050);
DISPLAY 0.617021 (-2275 3050);
PAINT SKYBLUE (-2275 3050);
FORCEPROP 1 LAST VOLTAGE 4V
J 0
(-2275 3100);
DISPLAY 0.617021 (-2275 3100);
PAINT SKYBLUE (-2275 3100);
FORCEPROP 1 LAST PART_NUMBER 602433-112
J 0
(-2275 3000);
DISPLAY 0.617021 (-2275 3000);
PAINT BLUE (-2275 3000);
FORCEPROP 1 LAST PACK_TYPE 0805
J 0
(-2275 2950);
DISPLAY 0.617021 (-2275 2950);
PAINT SKYBLUE (-2275 2950);
FORCEPROP 0 LAST BOM_SS NOPOP
J 0
(-2262 2768);
DISPLAY 0.638298 (-2262 2768);
PAINT BROWN (-2262 2768);
DISPLAY BOTH (-2262 2768);
FORCEPROP 0 LAST GROUP PWR_MLCC_CAP
J 0
(-2269 2812);
DISPLAY 0.638298 (-2269 2812);
PAINT BROWN (-2269 2812);
DISPLAY BOTH (-2269 2812);
FORCEPROP 0 LAST NEW_MATERIAL X6S
J 0
(-2275 2850);
DISPLAY 0.638298 (-2275 2850);
PAINT BROWN (-2275 2850);
DISPLAY BOTH (-2275 2850);
FORCEPROP 0 LAST NEW_PN 078.1071T.M002
J 0
(-2266 2898);
DISPLAY 0.638298 (-2266 2898);
PAINT BROWN (-2266 2898);
DISPLAY BOTH (-2266 2898);
FORCEPROP 0 LAST CDS_SEC 1
J 0
(-2275 3250);
PAINT MONO (-2275 3250);
DISPLAY INVISIBLE (-2275 3250);
FORCEPROP 2 LAST CDS_LIB mstr_discrete
J 0
(-2325 3100);
PAINT MONO (-2325 3100);
DISPLAY INVISIBLE (-2325 3100);
FORCEPROP 2 LAST BOM_COST MEM_VRD_PVDDQ_CD
J 0
(-2275 3250);
PAINT MONO (-2275 3250);
DISPLAY INVISIBLE (-2275 3250);
FORCEPROP 2 LAST ROOM VDDQ_ABC_PWR_VR
J 0
(-2275 3250);
PAINT MONO (-2275 3250);
DISPLAY INVISIBLE (-2275 3250);
FORCEPROP 2 LAST SEC_TYPE 0805
J 0
(-2275 3300);
DISPLAY 1.021277 (-2275 3300);
PAINT ORANGE (-2275 3300);
DISPLAY INVISIBLE (-2275 3300);
FORCEPROP 2 LAST SEC 1
J 0
(-2275 3300);
DISPLAY 0.680851 (-2275 3300);
PAINT MONO (-2275 3300);
DISPLAY INVISIBLE (-2275 3300);
FORCEPROP 1 LAST MATERIAL X5R
J 0
(-2275 3000);
DISPLAY 0.617021 (-2275 3000);
PAINT SKYBLUE (-2275 3000);
DISPLAY INVISIBLE (-2275 3000);
FORCEPROP 1 LAST PATH I313
J 0
(-2275 3250);
DISPLAY 0.978723 (-2275 3250);
PAINT WHITE (-2275 3250);
DISPLAY INVISIBLE (-2275 3250);
FORCEPROP 2 LAST CDS_LOCATION C8P30
J 0
(-2275 3200);
DISPLAY 0.617021 (-2275 3200);
PAINT AQUA (-2275 3200);
DISPLAY INVISIBLE (-2275 3200);
FORCEADD CAP..1
(-1975 3100);
FORCEPROP 1 LAST PACK_TYPE 0805
J 0
(-1925 2950);
DISPLAY 0.617021 (-1925 2950);
PAINT SKYBLUE (-1925 2950);
FORCEPROP 1 LASTPIN (-1975 3200) $PN 1
J 0
(-1965 3180);
DISPLAY 0.617021 (-1965 3180);
PAINT ORANGE (-1965 3180);
FORCEPROP 1 LAST LOCATION C8P31
J 0
(-1925 3200);
DISPLAY 0.617021 (-1925 3200);
PAINT AQUA (-1925 3200);
FORCEPROP 1 LASTPIN (-1975 3000) $PN 2
J 0
(-1965 2980);
DISPLAY 0.617021 (-1965 2980);
PAINT ORANGE (-1965 2980);
FORCEPROP 1 LAST VALUE 100UF
J 0
(-1925 3150);
DISPLAY 0.617021 (-1925 3150);
PAINT SKYBLUE (-1925 3150);
FORCEPROP 1 LAST VOLTAGE 4V
J 0
(-1925 3100);
DISPLAY 0.617021 (-1925 3100);
PAINT SKYBLUE (-1925 3100);
FORCEPROP 1 LAST TOLERANCE 20%
J 0
(-1925 3050);
DISPLAY 0.617021 (-1925 3050);
PAINT SKYBLUE (-1925 3050);
FORCEPROP 1 LAST PART_NUMBER 602433-112
J 0
(-1925 3000);
DISPLAY 0.617021 (-1925 3000);
PAINT BLUE (-1925 3000);
FORCEPROP 0 LAST BOM_SS NOPOP
J 0
(-1912 2668);
DISPLAY 0.638298 (-1912 2668);
PAINT BROWN (-1912 2668);
DISPLAY BOTH (-1912 2668);
FORCEPROP 0 LAST GROUP PWR_MLCC_CAP
J 0
(-1919 2712);
DISPLAY 0.638298 (-1919 2712);
PAINT BROWN (-1919 2712);
DISPLAY BOTH (-1919 2712);
FORCEPROP 0 LAST NEW_MATERIAL X6S
J 0
(-1925 2750);
DISPLAY 0.638298 (-1925 2750);
PAINT BROWN (-1925 2750);
DISPLAY BOTH (-1925 2750);
FORCEPROP 0 LAST NEW_PN 078.1071T.M002
J 0
(-1916 2773);
DISPLAY 0.638298 (-1916 2773);
PAINT BROWN (-1916 2773);
DISPLAY BOTH (-1916 2773);
FORCEPROP 1 LAST PATH I314
J 0
(-1925 3250);
DISPLAY 0.978723 (-1925 3250);
PAINT WHITE (-1925 3250);
DISPLAY INVISIBLE (-1925 3250);
FORCEPROP 0 LAST CDS_SEC 1
J 0
(-1925 3250);
PAINT MONO (-1925 3250);
DISPLAY INVISIBLE (-1925 3250);
FORCEPROP 2 LAST CDS_LIB mstr_discrete
J 0
(-1975 3100);
PAINT MONO (-1975 3100);
DISPLAY INVISIBLE (-1975 3100);
FORCEPROP 2 LAST BOM_COST MEM_VRD_PVDDQ_CD
J 0
(-1925 3250);
PAINT MONO (-1925 3250);
DISPLAY INVISIBLE (-1925 3250);
FORCEPROP 2 LAST ROOM VDDQ_ABC_PWR_VR
J 0
(-1925 3250);
PAINT MONO (-1925 3250);
DISPLAY INVISIBLE (-1925 3250);
FORCEPROP 2 LAST SEC_TYPE 0805
J 0
(-1925 3300);
DISPLAY 1.021277 (-1925 3300);
PAINT ORANGE (-1925 3300);
DISPLAY INVISIBLE (-1925 3300);
FORCEPROP 2 LAST SEC 1
J 0
(-1925 3300);
DISPLAY 0.680851 (-1925 3300);
PAINT MONO (-1925 3300);
DISPLAY INVISIBLE (-1925 3300);
FORCEPROP 1 LAST MATERIAL X5R
J 0
(-1925 3000);
DISPLAY 0.617021 (-1925 3000);
PAINT SKYBLUE (-1925 3000);
DISPLAY INVISIBLE (-1925 3000);
FORCEPROP 2 LAST CDS_LOCATION C8P31
J 0
(-1925 3200);
DISPLAY 0.617021 (-1925 3200);
PAINT AQUA (-1925 3200);
DISPLAY INVISIBLE (-1925 3200);
FORCEADD CAP..1
(100 3025);
FORCEPROP 0 LAST NEW_PN 078.1071T.M002
J 0
(159 2823);
DISPLAY 0.638298 (159 2823);
PAINT BROWN (159 2823);
DISPLAY BOTH (159 2823);
FORCEPROP 0 LAST NEW_MATERIAL X6S
J 0
(150 2775);
DISPLAY 0.638298 (150 2775);
PAINT BROWN (150 2775);
DISPLAY BOTH (150 2775);
FORCEPROP 0 LAST GROUP PWR_MLCC_CAP
J 0
(156 2737);
DISPLAY 0.638298 (156 2737);
PAINT BROWN (156 2737);
DISPLAY BOTH (156 2737);
FORCEPROP 1 LAST PACK_TYPE 0805
J 0
(150 2875);
DISPLAY 0.617021 (150 2875);
PAINT SKYBLUE (150 2875);
FORCEPROP 1 LAST PART_NUMBER 602433-112
J 0
(150 2925);
DISPLAY 0.617021 (150 2925);
PAINT BLUE (150 2925);
FORCEPROP 1 LAST VALUE 100UF
J 0
(150 3075);
DISPLAY 0.617021 (150 3075);
PAINT SKYBLUE (150 3075);
FORCEPROP 1 LAST VOLTAGE 4V
J 0
(150 3025);
DISPLAY 0.617021 (150 3025);
PAINT SKYBLUE (150 3025);
FORCEPROP 1 LAST TOLERANCE 20%
J 0
(150 2975);
DISPLAY 0.617021 (150 2975);
PAINT SKYBLUE (150 2975);
FORCEPROP 1 LASTPIN (100 2925) $PN 2
J 0
(110 2905);
DISPLAY 0.617021 (110 2905);
PAINT ORANGE (110 2905);
FORCEPROP 1 LASTPIN (100 3125) $PN 1
J 0
(110 3105);
DISPLAY 0.617021 (110 3105);
PAINT ORANGE (110 3105);
FORCEPROP 1 LAST LOCATION C8P34
J 0
(150 3125);
DISPLAY 0.617021 (150 3125);
PAINT AQUA (150 3125);
FORCEPROP 0 LAST BOM_SS NOPOP
J 0
(138 2693);
DISPLAY 0.638298 (138 2693);
PAINT BROWN (138 2693);
DISPLAY BOTH (138 2693);
FORCEPROP 1 LAST MATERIAL X5R
J 0
(150 2925);
DISPLAY 0.617021 (150 2925);
PAINT SKYBLUE (150 2925);
DISPLAY INVISIBLE (150 2925);
FORCEPROP 2 LAST SEC 1
J 0
(150 3225);
DISPLAY 0.680851 (150 3225);
PAINT MONO (150 3225);
DISPLAY INVISIBLE (150 3225);
FORCEPROP 2 LAST SEC_TYPE 0805
J 0
(150 3225);
DISPLAY 1.021277 (150 3225);
PAINT ORANGE (150 3225);
DISPLAY INVISIBLE (150 3225);
FORCEPROP 2 LAST ROOM VDDQ_ABC_PWR_VR
J 0
(150 3175);
PAINT MONO (150 3175);
DISPLAY INVISIBLE (150 3175);
FORCEPROP 2 LAST BOM_COST MEM_VRD_PVDDQ_CD
J 0
(150 3175);
PAINT MONO (150 3175);
DISPLAY INVISIBLE (150 3175);
FORCEPROP 2 LAST CDS_LIB mstr_discrete
J 0
(100 3025);
PAINT MONO (100 3025);
DISPLAY INVISIBLE (100 3025);
FORCEPROP 0 LAST CDS_SEC 1
J 0
(150 3175);
PAINT MONO (150 3175);
DISPLAY INVISIBLE (150 3175);
FORCEPROP 1 LAST PATH I315
J 0
(150 3175);
DISPLAY 0.978723 (150 3175);
PAINT WHITE (150 3175);
DISPLAY INVISIBLE (150 3175);
FORCEPROP 2 LAST CDS_LOCATION C8P34
J 0
(150 3125);
DISPLAY 0.617021 (150 3125);
PAINT AQUA (150 3125);
DISPLAY INVISIBLE (150 3125);
FORCEADD CAP..1
(450 3025);
FORCEPROP 0 LAST GROUP PWR_MLCC_CAP
J 0
(506 2612);
DISPLAY 0.638298 (506 2612);
PAINT BROWN (506 2612);
DISPLAY BOTH (506 2612);
FORCEPROP 1 LAST LOCATION C8P33
J 0
(500 3125);
DISPLAY 0.617021 (500 3125);
PAINT AQUA (500 3125);
FORCEPROP 1 LAST TOLERANCE 20%
J 0
(500 2975);
DISPLAY 0.617021 (500 2975);
PAINT SKYBLUE (500 2975);
FORCEPROP 1 LASTPIN (450 3125) $PN 1
J 0
(460 3105);
DISPLAY 0.617021 (460 3105);
PAINT ORANGE (460 3105);
FORCEPROP 1 LASTPIN (450 2925) $PN 2
J 0
(460 2905);
DISPLAY 0.617021 (460 2905);
PAINT ORANGE (460 2905);
FORCEPROP 1 LAST PACK_TYPE 0805
J 0
(500 2875);
DISPLAY 0.617021 (500 2875);
PAINT SKYBLUE (500 2875);
FORCEPROP 1 LAST VALUE 100UF
J 0
(500 3075);
DISPLAY 0.617021 (500 3075);
PAINT SKYBLUE (500 3075);
FORCEPROP 0 LAST NEW_MATERIAL X6S
J 0
(500 2675);
DISPLAY 0.638298 (500 2675);
PAINT BROWN (500 2675);
DISPLAY BOTH (500 2675);
FORCEPROP 1 LAST PART_NUMBER 602433-112
J 0
(500 2925);
DISPLAY 0.617021 (500 2925);
PAINT BLUE (500 2925);
FORCEPROP 0 LAST BOM_SS NOPOP
J 0
(513 2568);
DISPLAY 0.638298 (513 2568);
PAINT BROWN (513 2568);
DISPLAY BOTH (513 2568);
FORCEPROP 0 LAST NEW_PN 078.1071T.M002
J 0
(509 2698);
DISPLAY 0.638298 (509 2698);
PAINT BROWN (509 2698);
DISPLAY BOTH (509 2698);
FORCEPROP 1 LAST VOLTAGE 4V
J 0
(500 3025);
DISPLAY 0.617021 (500 3025);
PAINT SKYBLUE (500 3025);
FORCEPROP 0 LAST CDS_SEC 1
J 0
(500 3175);
PAINT MONO (500 3175);
DISPLAY INVISIBLE (500 3175);
FORCEPROP 2 LAST CDS_LIB mstr_discrete
J 0
(450 3025);
PAINT MONO (450 3025);
DISPLAY INVISIBLE (450 3025);
FORCEPROP 2 LAST BOM_COST MEM_VRD_PVDDQ_CD
J 0
(500 3175);
PAINT MONO (500 3175);
DISPLAY INVISIBLE (500 3175);
FORCEPROP 2 LAST ROOM VDDQ_ABC_PWR_VR
J 0
(500 3175);
PAINT MONO (500 3175);
DISPLAY INVISIBLE (500 3175);
FORCEPROP 2 LAST SEC_TYPE 0805
J 0
(500 3225);
DISPLAY 1.021277 (500 3225);
PAINT ORANGE (500 3225);
DISPLAY INVISIBLE (500 3225);
FORCEPROP 2 LAST SEC 1
J 0
(500 3225);
DISPLAY 0.680851 (500 3225);
PAINT MONO (500 3225);
DISPLAY INVISIBLE (500 3225);
FORCEPROP 1 LAST MATERIAL X5R
J 0
(500 2925);
DISPLAY 0.617021 (500 2925);
PAINT SKYBLUE (500 2925);
DISPLAY INVISIBLE (500 2925);
FORCEPROP 1 LAST PATH I316
J 0
(500 3175);
DISPLAY 0.978723 (500 3175);
PAINT WHITE (500 3175);
DISPLAY INVISIBLE (500 3175);
FORCEPROP 2 LAST CDS_LOCATION C8P33
J 0
(500 3125);
DISPLAY 0.617021 (500 3125);
PAINT AQUA (500 3125);
DISPLAY INVISIBLE (500 3125);
FORCEADD CAP..1
(800 3025);
FORCEPROP 1 LAST VALUE 100UF
J 0
(850 3075);
DISPLAY 0.617021 (850 3075);
PAINT SKYBLUE (850 3075);
FORCEPROP 1 LAST TOLERANCE 20%
J 0
(850 2975);
DISPLAY 0.617021 (850 2975);
PAINT SKYBLUE (850 2975);
FORCEPROP 1 LAST PART_NUMBER 602433-112
J 0
(850 2925);
DISPLAY 0.617021 (850 2925);
PAINT BLUE (850 2925);
FORCEPROP 1 LAST PACK_TYPE 0805
J 0
(850 2875);
DISPLAY 0.617021 (850 2875);
PAINT SKYBLUE (850 2875);
FORCEPROP 1 LAST VOLTAGE 4V
J 0
(850 3025);
DISPLAY 0.617021 (850 3025);
PAINT SKYBLUE (850 3025);
FORCEPROP 1 LASTPIN (800 2925) $PN 2
J 0
(810 2905);
DISPLAY 0.617021 (810 2905);
PAINT ORANGE (810 2905);
FORCEPROP 1 LASTPIN (800 3125) $PN 1
J 0
(810 3105);
DISPLAY 0.617021 (810 3105);
PAINT ORANGE (810 3105);
FORCEPROP 0 LAST NEW_MATERIAL X6S
J 0
(850 2775);
DISPLAY 0.638298 (850 2775);
PAINT BROWN (850 2775);
DISPLAY BOTH (850 2775);
FORCEPROP 0 LAST GROUP PWR_MLCC_CAP
J 0
(931 2737);
DISPLAY 0.638298 (931 2737);
PAINT BROWN (931 2737);
DISPLAY BOTH (931 2737);
FORCEPROP 0 LAST BOM_SS NOPOP
J 0
(938 2668);
DISPLAY 0.638298 (938 2668);
PAINT BROWN (938 2668);
DISPLAY BOTH (938 2668);
FORCEPROP 0 LAST NEW_PN 078.1071T.M002
J 0
(859 2823);
DISPLAY 0.638298 (859 2823);
PAINT BROWN (859 2823);
DISPLAY BOTH (859 2823);
FORCEPROP 1 LAST LOCATION C8P32
J 0
(850 3125);
DISPLAY 0.617021 (850 3125);
PAINT AQUA (850 3125);
FORCEPROP 1 LAST PATH I317
J 0
(850 3175);
DISPLAY 0.978723 (850 3175);
PAINT WHITE (850 3175);
DISPLAY INVISIBLE (850 3175);
FORCEPROP 1 LAST MATERIAL X5R
J 0
(850 2925);
DISPLAY 0.617021 (850 2925);
PAINT SKYBLUE (850 2925);
DISPLAY INVISIBLE (850 2925);
FORCEPROP 2 LAST SEC 1
J 0
(850 3225);
DISPLAY 0.680851 (850 3225);
PAINT MONO (850 3225);
DISPLAY INVISIBLE (850 3225);
FORCEPROP 2 LAST SEC_TYPE 0805
J 0
(850 3225);
DISPLAY 1.021277 (850 3225);
PAINT ORANGE (850 3225);
DISPLAY INVISIBLE (850 3225);
FORCEPROP 2 LAST ROOM VDDQ_ABC_PWR_VR
J 0
(850 3175);
PAINT MONO (850 3175);
DISPLAY INVISIBLE (850 3175);
FORCEPROP 2 LAST BOM_COST MEM_VRD_PVDDQ_CD
J 0
(850 3175);
PAINT MONO (850 3175);
DISPLAY INVISIBLE (850 3175);
FORCEPROP 2 LAST CDS_LIB mstr_discrete
J 0
(800 3025);
PAINT MONO (800 3025);
DISPLAY INVISIBLE (800 3025);
FORCEPROP 0 LAST CDS_SEC 1
J 0
(850 3175);
PAINT MONO (850 3175);
DISPLAY INVISIBLE (850 3175);
FORCEPROP 2 LAST CDS_LOCATION C8P32
J 0
(850 3125);
DISPLAY 0.617021 (850 3125);
PAINT AQUA (850 3125);
DISPLAY INVISIBLE (850 3125);
FORCEADD CAP..1
(1625 3050);
FORCEPROP 1 LAST PART_NUMBER 602433-112
J 0
(1675 2950);
DISPLAY 0.617021 (1675 2950);
PAINT BLUE (1675 2950);
FORCEPROP 1 LAST TOLERANCE 20%
J 0
(1675 3000);
DISPLAY 0.617021 (1675 3000);
PAINT SKYBLUE (1675 3000);
FORCEPROP 1 LAST VOLTAGE 4V
J 0
(1675 3050);
DISPLAY 0.617021 (1675 3050);
PAINT SKYBLUE (1675 3050);
FORCEPROP 1 LAST PACK_TYPE 0805
J 0
(1675 2900);
DISPLAY 0.617021 (1675 2900);
PAINT SKYBLUE (1675 2900);
FORCEPROP 1 LASTPIN (1625 2950) $PN 2
J 0
(1635 2930);
DISPLAY 0.617021 (1635 2930);
PAINT ORANGE (1635 2930);
FORCEPROP 0 LAST GROUP PWR_MLCC_CAP
J 0
(1681 2762);
DISPLAY 0.638298 (1681 2762);
PAINT BROWN (1681 2762);
DISPLAY BOTH (1681 2762);
FORCEPROP 1 LASTPIN (1625 3150) $PN 1
J 0
(1635 3130);
DISPLAY 0.617021 (1635 3130);
PAINT ORANGE (1635 3130);
FORCEPROP 0 LAST BOM_SS NOPOP
J 0
(1738 3218);
DISPLAY 0.638298 (1738 3218);
PAINT BROWN (1738 3218);
DISPLAY BOTH (1738 3218);
FORCEPROP 1 LAST LOCATION C7P20
J 0
(1675 3150);
DISPLAY 0.617021 (1675 3150);
PAINT AQUA (1675 3150);
FORCEPROP 1 LAST VALUE 100UF
J 0
(1675 3100);
DISPLAY 0.617021 (1675 3100);
PAINT SKYBLUE (1675 3100);
FORCEPROP 0 LAST NEW_MATERIAL X6S
J 0
(1675 2800);
DISPLAY 0.638298 (1675 2800);
PAINT BROWN (1675 2800);
DISPLAY BOTH (1675 2800);
FORCEPROP 0 LAST NEW_PN 078.1071T.M002
J 0
(1684 2848);
DISPLAY 0.638298 (1684 2848);
PAINT BROWN (1684 2848);
DISPLAY BOTH (1684 2848);
FORCEPROP 1 LAST MATERIAL X5R
J 0
(1675 2950);
DISPLAY 0.617021 (1675 2950);
PAINT SKYBLUE (1675 2950);
DISPLAY INVISIBLE (1675 2950);
FORCEPROP 2 LAST SEC 1
J 0
(1675 3250);
DISPLAY 0.680851 (1675 3250);
PAINT MONO (1675 3250);
DISPLAY INVISIBLE (1675 3250);
FORCEPROP 2 LAST SEC_TYPE 0805
J 0
(1675 3250);
DISPLAY 1.021277 (1675 3250);
PAINT ORANGE (1675 3250);
DISPLAY INVISIBLE (1675 3250);
FORCEPROP 2 LAST ROOM VDDQ_ABC_PWR_VR
J 0
(1675 3200);
PAINT MONO (1675 3200);
DISPLAY INVISIBLE (1675 3200);
FORCEPROP 2 LAST BOM_COST MEM_VRD_PVDDQ_CD
J 0
(1675 3200);
PAINT MONO (1675 3200);
DISPLAY INVISIBLE (1675 3200);
FORCEPROP 2 LAST CDS_LIB mstr_discrete
J 0
(1625 3050);
PAINT MONO (1625 3050);
DISPLAY INVISIBLE (1625 3050);
FORCEPROP 0 LAST CDS_SEC 1
J 0
(1675 3200);
PAINT MONO (1675 3200);
DISPLAY INVISIBLE (1675 3200);
FORCEPROP 1 LAST PATH I318
J 0
(1675 3200);
DISPLAY 0.978723 (1675 3200);
PAINT WHITE (1675 3200);
DISPLAY INVISIBLE (1675 3200);
FORCEPROP 2 LAST CDS_LOCATION C7P20
J 0
(1675 3150);
DISPLAY 0.617021 (1675 3150);
PAINT AQUA (1675 3150);
DISPLAY INVISIBLE (1675 3150);
FORCEADD CAP..1
(5000 2825);
FORCEPROP 0 LAST BOM_SS NOPOP
J 0
(5013 2293);
DISPLAY 0.638298 (5013 2293);
PAINT BROWN (5013 2293);
DISPLAY BOTH (5013 2293);
FORCEPROP 1 LAST VALUE 100UF
J 0
(5050 2875);
DISPLAY 0.617021 (5050 2875);
PAINT SKYBLUE (5050 2875);
FORCEPROP 1 LAST LOCATION C8U1
J 0
(5050 2925);
DISPLAY 0.617021 (5050 2925);
PAINT AQUA (5050 2925);
FORCEPROP 1 LAST PART_NUMBER 602433-112
J 0
(5050 2725);
DISPLAY 0.617021 (5050 2725);
PAINT BLUE (5050 2725);
FORCEPROP 0 LAST NEW_MATERIAL X6S
J 0
(5025 2350);
DISPLAY 0.638298 (5025 2350);
PAINT BROWN (5025 2350);
DISPLAY BOTH (5025 2350);
FORCEPROP 0 LAST GROUP PWR_MLCC_CAP
J 0
(5031 2262);
DISPLAY 0.638298 (5031 2262);
PAINT BROWN (5031 2262);
DISPLAY BOTH (5031 2262);
FORCEPROP 1 LASTPIN (5000 2925) $PN 1
J 0
(5010 2905);
DISPLAY 0.617021 (5010 2905);
PAINT ORANGE (5010 2905);
FORCEPROP 1 LASTPIN (5000 2725) $PN 2
J 0
(5010 2705);
DISPLAY 0.617021 (5010 2705);
PAINT ORANGE (5010 2705);
FORCEPROP 1 LAST TOLERANCE 20%
J 0
(5050 2775);
DISPLAY 0.617021 (5050 2775);
PAINT SKYBLUE (5050 2775);
FORCEPROP 1 LAST VOLTAGE 4V
J 0
(5050 2825);
DISPLAY 0.617021 (5050 2825);
PAINT SKYBLUE (5050 2825);
FORCEPROP 1 LAST PACK_TYPE 0805
J 0
(5050 2675);
DISPLAY 0.617021 (5050 2675);
PAINT SKYBLUE (5050 2675);
FORCEPROP 0 LAST NEW_PN 078.1071T.M002
J 0
(5034 2398);
DISPLAY 0.638298 (5034 2398);
PAINT BROWN (5034 2398);
DISPLAY BOTH (5034 2398);
FORCEPROP 0 LAST CDS_SEC 1
J 0
(5050 2975);
PAINT MONO (5050 2975);
DISPLAY INVISIBLE (5050 2975);
FORCEPROP 2 LAST CDS_LIB mstr_discrete
J 0
(5000 2825);
PAINT MONO (5000 2825);
DISPLAY INVISIBLE (5000 2825);
FORCEPROP 2 LAST BOM_COST MEM_VRD_PVDDQ_CD
J 0
(5050 2975);
PAINT MONO (5050 2975);
DISPLAY INVISIBLE (5050 2975);
FORCEPROP 2 LAST ROOM VDDQ_ABC_PWR_VR
J 0
(5050 2975);
PAINT MONO (5050 2975);
DISPLAY INVISIBLE (5050 2975);
FORCEPROP 2 LAST SEC_TYPE 0805
J 0
(5050 3025);
DISPLAY 1.021277 (5050 3025);
PAINT ORANGE (5050 3025);
DISPLAY INVISIBLE (5050 3025);
FORCEPROP 2 LAST SEC 1
J 0
(5050 3025);
DISPLAY 0.680851 (5050 3025);
PAINT MONO (5050 3025);
DISPLAY INVISIBLE (5050 3025);
FORCEPROP 1 LAST MATERIAL X5R
J 0
(5050 2725);
DISPLAY 0.617021 (5050 2725);
PAINT SKYBLUE (5050 2725);
DISPLAY INVISIBLE (5050 2725);
FORCEPROP 1 LAST PATH I319
J 0
(5050 2975);
DISPLAY 0.978723 (5050 2975);
PAINT WHITE (5050 2975);
DISPLAY INVISIBLE (5050 2975);
FORCEPROP 2 LAST CDS_LOCATION C8U1
J 0
(5050 2925);
DISPLAY 0.617021 (5050 2925);
PAINT AQUA (5050 2925);
DISPLAY INVISIBLE (5050 2925);
FORCEADD CAP..1
(4600 2825);
FORCEPROP 0 LAST BOM_SS NOPOP
J 0
(4638 2518);
DISPLAY 0.638298 (4638 2518);
PAINT BROWN (4638 2518);
DISPLAY BOTH (4638 2518);
FORCEPROP 0 LAST GROUP PWR_MLCC_CAP
J 0
(4681 2462);
DISPLAY 0.638298 (4681 2462);
PAINT BROWN (4681 2462);
DISPLAY BOTH (4681 2462);
FORCEPROP 0 LAST NEW_MATERIAL X6S
J 0
(4650 2575);
DISPLAY 0.638298 (4650 2575);
PAINT BROWN (4650 2575);
DISPLAY BOTH (4650 2575);
FORCEPROP 1 LAST PART_NUMBER 602433-112
J 0
(4650 2725);
DISPLAY 0.617021 (4650 2725);
PAINT BLUE (4650 2725);
FORCEPROP 1 LAST PACK_TYPE 0805
J 0
(4650 2675);
DISPLAY 0.617021 (4650 2675);
PAINT SKYBLUE (4650 2675);
FORCEPROP 1 LAST TOLERANCE 20%
J 0
(4650 2775);
DISPLAY 0.617021 (4650 2775);
PAINT SKYBLUE (4650 2775);
FORCEPROP 1 LAST LOCATION C8U8
J 0
(4650 2925);
DISPLAY 0.617021 (4650 2925);
PAINT AQUA (4650 2925);
FORCEPROP 1 LASTPIN (4600 2925) $PN 1
J 0
(4610 2905);
DISPLAY 0.617021 (4610 2905);
PAINT ORANGE (4610 2905);
FORCEPROP 1 LASTPIN (4600 2725) $PN 2
J 0
(4610 2705);
DISPLAY 0.617021 (4610 2705);
PAINT ORANGE (4610 2705);
FORCEPROP 1 LAST VOLTAGE 4V
J 0
(4650 2825);
DISPLAY 0.617021 (4650 2825);
PAINT SKYBLUE (4650 2825);
FORCEPROP 1 LAST VALUE 100UF
J 0
(4650 2875);
DISPLAY 0.617021 (4650 2875);
PAINT SKYBLUE (4650 2875);
FORCEPROP 0 LAST NEW_PN 078.1071T.M002
J 0
(4659 2623);
DISPLAY 0.638298 (4659 2623);
PAINT BROWN (4659 2623);
DISPLAY BOTH (4659 2623);
FORCEPROP 1 LAST PATH I320
J 0
(4650 2975);
DISPLAY 0.978723 (4650 2975);
PAINT WHITE (4650 2975);
DISPLAY INVISIBLE (4650 2975);
FORCEPROP 0 LAST CDS_SEC 1
J 0
(4650 2975);
PAINT MONO (4650 2975);
DISPLAY INVISIBLE (4650 2975);
FORCEPROP 2 LAST CDS_LIB mstr_discrete
J 0
(4600 2825);
PAINT MONO (4600 2825);
DISPLAY INVISIBLE (4600 2825);
FORCEPROP 2 LAST BOM_COST MEM_VRD_PVDDQ_CD
J 0
(4650 2975);
PAINT MONO (4650 2975);
DISPLAY INVISIBLE (4650 2975);
FORCEPROP 2 LAST ROOM VDDQ_ABC_PWR_VR
J 0
(4650 2975);
PAINT MONO (4650 2975);
DISPLAY INVISIBLE (4650 2975);
FORCEPROP 2 LAST SEC_TYPE 0805
J 0
(4650 3025);
DISPLAY 1.021277 (4650 3025);
PAINT ORANGE (4650 3025);
DISPLAY INVISIBLE (4650 3025);
FORCEPROP 2 LAST SEC 1
J 0
(4650 3025);
DISPLAY 0.680851 (4650 3025);
PAINT MONO (4650 3025);
DISPLAY INVISIBLE (4650 3025);
FORCEPROP 1 LAST MATERIAL X5R
J 0
(4650 2725);
DISPLAY 0.617021 (4650 2725);
PAINT SKYBLUE (4650 2725);
DISPLAY INVISIBLE (4650 2725);
FORCEPROP 2 LAST CDS_LOCATION C8U8
J 0
(4650 2925);
DISPLAY 0.617021 (4650 2925);
PAINT AQUA (4650 2925);
DISPLAY INVISIBLE (4650 2925);
FORCEADD ST270U2D5VBM-GP..1
(-1250 1150);
FORCEPROP 0 LAST NEW_VALUE 33UF
R 1
J 0
(-1075 850);
DISPLAY 0.638298 (-1075 850);
PAINT GREEN (-1075 850);
DISPLAY BOTH (-1075 850);
FORCEPROP 0 LAST NEW_SIZE B2
R 1
J 0
(-1025 850);
DISPLAY 0.638298 (-1025 850);
PAINT GREEN (-1025 850);
DISPLAY BOTH (-1025 850);
FORCEPROP 2 LASTPIN (-1250 1225) $PN 1
R 1
J 0
(-1260 1235);
DISPLAY 0.808511 (-1260 1235);
PAINT ORANGE (-1260 1235);
FORCEPROP 2 LASTPIN (-1250 1075) $PN 2
R 1
J 2
(-1260 1065);
DISPLAY 0.808511 (-1260 1065);
PAINT ORANGE (-1260 1065);
FORCEPROP 1 LAST LOCATION C1G15
R 1
J 0
(-1175 1080);
DISPLAY 0.617021 (-1175 1080);
PAINT GREEN (-1175 1080);
FORCEPROP 0 LAST NEW_PN 077.C3361.0001
R 1
J 0
(-1125 850);
DISPLAY 0.638298 (-1125 850);
PAINT GREEN (-1125 850);
DISPLAY BOTH (-1125 850);
FORCEPROP 1 LAST CDS_LMAN_SYM_OUTLINE -50,25,50,-25
J 0
(-1250 1150);
DISPLAY 0.468085 (-1250 1150);
PAINT GREEN (-1250 1150);
DISPLAY INVISIBLE (-1250 1150);
FORCEPROP 2 LAST CDS_LIB w_hdl
J 0
(-1250 1150);
DISPLAY INVISIBLE (-1250 1150);
FORCEPROP 1 LAST PART_NUMBER 077.C2771.0001
J 0
(-1250 1110);
DISPLAY 0.617021 (-1250 1110);
PAINT GREEN (-1250 1110);
DISPLAY INVISIBLE (-1250 1110);
FORCEPROP 2 LAST SEC_TYPE SMD-TCG2
J 0
(-1225 1225);
DISPLAY 1.021277 (-1225 1225);
PAINT ORANGE (-1225 1225);
DISPLAY INVISIBLE (-1225 1225);
FORCEPROP 2 LAST SEC 1
J 0
(-1225 1225);
DISPLAY 0.680851 (-1225 1225);
PAINT MONO (-1225 1225);
DISPLAY INVISIBLE (-1225 1225);
FORCEPROP 1 LAST PACK_TYPE SMD-TCG2
J 0
(-1250 1150);
DISPLAY 0.617021 (-1250 1150);
PAINT GREEN (-1250 1150);
DISPLAY INVISIBLE (-1250 1150);
FORCEPROP 1 LAST VALUE ST270U2D5VBM-GP
J 0
(-1225 1100);
DISPLAY 0.617021 (-1225 1100);
PAINT GREEN (-1225 1100);
DISPLAY INVISIBLE (-1225 1100);
FORCEPROP 1 LAST PATH I327
J 0
(-1250 1190);
DISPLAY 0.617021 (-1250 1190);
PAINT GREEN (-1250 1190);
DISPLAY INVISIBLE (-1250 1190);
FORCEADD ST270U2D5VBM-GP..1
(-550 1150);
FORCEPROP 2 LASTPIN (-550 1075) $PN 2
R 1
J 2
(-560 1065);
DISPLAY 0.808511 (-560 1065);
PAINT ORANGE (-560 1065);
FORCEPROP 2 LASTPIN (-550 1225) $PN 1
R 1
J 0
(-560 1235);
DISPLAY 0.808511 (-560 1235);
PAINT ORANGE (-560 1235);
FORCEPROP 0 LAST NEW_PN 077.C3361.0001
R 1
J 0
(-425 850);
DISPLAY 0.638298 (-425 850);
PAINT GREEN (-425 850);
DISPLAY BOTH (-425 850);
FORCEPROP 0 LAST NEW_SIZE B2
R 1
J 0
(-325 850);
DISPLAY 0.638298 (-325 850);
PAINT GREEN (-325 850);
DISPLAY BOTH (-325 850);
FORCEPROP 0 LAST NEW_VALUE 33UF
R 1
J 0
(-375 850);
DISPLAY 0.638298 (-375 850);
PAINT GREEN (-375 850);
DISPLAY BOTH (-375 850);
FORCEPROP 1 LAST LOCATION C1G12
R 1
J 0
(-475 1080);
DISPLAY 0.617021 (-475 1080);
PAINT GREEN (-475 1080);
FORCEPROP 1 LAST PART_NUMBER 077.C2771.0001
J 0
(-550 1110);
DISPLAY 0.617021 (-550 1110);
PAINT GREEN (-550 1110);
DISPLAY INVISIBLE (-550 1110);
FORCEPROP 1 LAST PACK_TYPE SMD-TCG2
J 0
(-550 1150);
DISPLAY 0.617021 (-550 1150);
PAINT GREEN (-550 1150);
DISPLAY INVISIBLE (-550 1150);
FORCEPROP 1 LAST VALUE ST270U2D5VBM-GP
J 0
(-525 1100);
DISPLAY 0.617021 (-525 1100);
PAINT GREEN (-525 1100);
DISPLAY INVISIBLE (-525 1100);
FORCEPROP 1 LAST PATH I328
J 0
(-550 1190);
DISPLAY 0.617021 (-550 1190);
PAINT GREEN (-550 1190);
DISPLAY INVISIBLE (-550 1190);
FORCEPROP 2 LAST SEC_TYPE SMD-TCG2
J 0
(-525 1225);
DISPLAY 1.021277 (-525 1225);
PAINT ORANGE (-525 1225);
DISPLAY INVISIBLE (-525 1225);
FORCEPROP 2 LAST SEC 1
J 0
(-525 1225);
DISPLAY 0.680851 (-525 1225);
PAINT MONO (-525 1225);
DISPLAY INVISIBLE (-525 1225);
FORCEPROP 1 LAST CDS_LMAN_SYM_OUTLINE -50,25,50,-25
J 0
(-550 1150);
DISPLAY 0.468085 (-550 1150);
PAINT GREEN (-550 1150);
DISPLAY INVISIBLE (-550 1150);
FORCEPROP 2 LAST CDS_LIB w_hdl
J 0
(-550 1150);
DISPLAY INVISIBLE (-550 1150);
FORCEADD ST270U2D5VBM-GP..1
(850 1150);
FORCEPROP 1 LAST LOCATION C1G7
R 1
J 0
(925 1080);
DISPLAY 0.617021 (925 1080);
PAINT GREEN (925 1080);
FORCEPROP 0 LAST NEW_PN 077.C3361.0001
R 1
J 0
(975 850);
DISPLAY 0.638298 (975 850);
PAINT GREEN (975 850);
DISPLAY BOTH (975 850);
FORCEPROP 0 LAST NEW_VALUE 33UF
R 1
J 0
(1025 850);
DISPLAY 0.638298 (1025 850);
PAINT GREEN (1025 850);
DISPLAY BOTH (1025 850);
FORCEPROP 0 LAST NEW_SIZE B2
R 1
J 0
(1075 850);
DISPLAY 0.638298 (1075 850);
PAINT GREEN (1075 850);
DISPLAY BOTH (1075 850);
FORCEPROP 2 LASTPIN (850 1075) $PN 2
R 1
J 2
(840 1065);
DISPLAY 0.808511 (840 1065);
PAINT ORANGE (840 1065);
FORCEPROP 2 LASTPIN (850 1225) $PN 1
R 1
J 0
(840 1235);
DISPLAY 0.808511 (840 1235);
PAINT ORANGE (840 1235);
FORCEPROP 2 LAST SEC_TYPE SMD-TCG2
J 0
(850 1225);
DISPLAY 1.021277 (850 1225);
PAINT ORANGE (850 1225);
DISPLAY INVISIBLE (850 1225);
FORCEPROP 2 LAST SEC 1
J 0
(850 1225);
DISPLAY 0.680851 (850 1225);
PAINT MONO (850 1225);
DISPLAY INVISIBLE (850 1225);
FORCEPROP 1 LAST PACK_TYPE SMD-TCG2
J 0
(850 1150);
DISPLAY 0.617021 (850 1150);
PAINT GREEN (850 1150);
DISPLAY INVISIBLE (850 1150);
FORCEPROP 2 LAST CDS_LIB w_hdl
J 0
(850 1150);
DISPLAY INVISIBLE (850 1150);
FORCEPROP 1 LAST PATH I329
J 0
(850 1190);
DISPLAY 0.617021 (850 1190);
PAINT GREEN (850 1190);
DISPLAY INVISIBLE (850 1190);
FORCEPROP 1 LAST CDS_LMAN_SYM_OUTLINE -50,25,50,-25
J 0
(850 1150);
DISPLAY 0.468085 (850 1150);
PAINT GREEN (850 1150);
DISPLAY INVISIBLE (850 1150);
FORCEPROP 1 LAST PART_NUMBER 077.C2771.0001
J 0
(850 1110);
DISPLAY 0.617021 (850 1110);
PAINT GREEN (850 1110);
DISPLAY INVISIBLE (850 1110);
FORCEPROP 1 LAST VALUE ST270U2D5VBM-GP
J 0
(875 1100);
DISPLAY 0.617021 (875 1100);
PAINT GREEN (875 1100);
DISPLAY INVISIBLE (875 1100);
FORCEADD RES..2
(4450 -25);
FORCEPROP 1 LAST LOCATION R1G20
J 0
(4495 100);
DISPLAY 0.617021 (4495 100);
PAINT AQUA (4495 100);
FORCEPROP 1 LAST MATERIAL CHIP
J 0
(4490 -100);
DISPLAY 0.617021 (4490 -100);
PAINT SKYBLUE (4490 -100);
FORCEPROP 1 LAST WATTAGE 1/10W
J 0
(4490 -50);
DISPLAY 0.617021 (4490 -50);
PAINT SKYBLUE (4490 -50);
FORCEPROP 1 LASTPIN (4450 -125) $PN 2
J 0
(4455 -115);
DISPLAY 0.617021 (4455 -115);
PAINT GREEN (4455 -115);
FORCEPROP 1 LASTPIN (4450 75) $PN 1
J 0
(4455 37);
DISPLAY 0.617021 (4455 37);
PAINT GREEN (4455 37);
FORCEPROP 1 LAST PACK_TYPE 0603
J 0
(4490 -200);
DISPLAY 0.617021 (4490 -200);
PAINT SKYBLUE (4490 -200);
FORCEPROP 1 LAST PART_NUMBER G22026-003
J 0
(4490 -150);
DISPLAY 0.617021 (4490 -150);
PAINT BLUE (4490 -150);
FORCEPROP 1 LAST TOLERANCE 1%
J 0
(4495 0);
DISPLAY 0.617021 (4495 0);
PAINT SKYBLUE (4495 0);
FORCEPROP 1 LAST VALUE 120.0
J 0
(4495 50);
DISPLAY 0.617021 (4495 50);
PAINT SKYBLUE (4495 50);
FORCEPROP 2 LAST CDS_LIB mstr_discrete
J 0
(4450 -25);
PAINT ORANGE (4450 -25);
DISPLAY INVISIBLE (4450 -25);
FORCEPROP 2 LAST BOM_COST MEM_VRD_PVPP_AB
J 0
(4500 150);
PAINT MONO (4500 150);
DISPLAY INVISIBLE (4500 150);
FORCEPROP 2 LAST CDS_SEC 1
J 0
(4500 200);
PAINT MONO (4500 200);
DISPLAY INVISIBLE (4500 200);
FORCEPROP 2 LAST $SEC 1
J 0
(4500 200);
PAINT MONO (4500 200);
DISPLAY INVISIBLE (4500 200);
FORCEPROP 2 LAST CDS_LOCATION R1G20
J 0
(4495 100);
DISPLAY 0.617021 (4495 100);
PAINT AQUA (4495 100);
DISPLAY INVISIBLE (4495 100);
FORCEPROP 1 LAST PATH I58
J 0
(4500 150);
DISPLAY 0.978723 (4500 150);
PAINT GREEN (4500 150);
DISPLAY INVISIBLE (4500 150);
FORCEPROP 2 LAST ROOM VDDQ_GHJ_PWR_VR
J 0
(4500 150);
PAINT MONO (4500 150);
DISPLAY INVISIBLE (4500 150);
FORCEADD GND..1
(100 1750);
FORCEPROP 3 LASTPIN (100 1800) SIG_NAME GND\g
J 0
(110 1810);
DISPLAY 0.659574 (110 1810);
PAINT MONO (110 1810);
DISPLAY INVISIBLE (110 1810);
FORCEPROP 2 LAST ROOM VDDQ_GHJ_PWR_VR
J 0
(-450 1825);
PAINT ORANGE (-450 1825);
DISPLAY INVISIBLE (-450 1825);
FORCEPROP 2 LAST BOM_COST MEM_VRD_PVPP_AB
J 0
(-225 1825);
PAINT MONO (-225 1825);
DISPLAY INVISIBLE (-225 1825);
FORCEPROP 1 LAST VOLTAGE 0
J 0
(100 1750);
PAINT SKYBLUE (100 1750);
DISPLAY INVISIBLE (100 1750);
FORCEPROP 2 LAST CDS_LIB mstr_symbols
J 0
(100 1750);
PAINT ORANGE (100 1750);
DISPLAY INVISIBLE (100 1750);
FORCEPROP 1 LAST SIZE 1B
J 0
(175 1700);
DISPLAY 0.893617 (175 1700);
PAINT GREEN (175 1700);
DISPLAY INVISIBLE (175 1700);
FORCEPROP 1 LAST PATH I65
J 0
(175 1750);
DISPLAY 1.170213 (175 1750);
PAINT AQUA (175 1750);
DISPLAY INVISIBLE (175 1750);
FORCEPROP 1 LAST BODY_TYPE PLUMBING
J 0
(55 1707);
DISPLAY 0.340426 (55 1707);
PAINT GREEN (55 1707);
DISPLAY INVISIBLE (55 1707);
FORCEPROP 1 LAST HDL_POWER GND
J 0
(100 1900);
DISPLAY 0.893617 (100 1900);
PAINT GREEN (100 1900);
DISPLAY INVISIBLE (100 1900);
FORCEADD OFFPAGE..1
(-1925 2050);
FORCEPROP 2 LAST $XR0 223 
J 0
(-2177 2050);
DISPLAY 0.638298 (-2177 2050);
PAINT MONO (-2177 2050);
FORCEPROP 2 LAST BOM_COST MEM_VRD_PVPP_AB
J 0
(-2200 2100);
PAINT MONO (-2200 2100);
DISPLAY INVISIBLE (-2200 2100);
FORCEPROP 2 LAST CDS_LIB mstr_standard
J 0
(-1925 2050);
PAINT ORANGE (-1925 2050);
DISPLAY INVISIBLE (-1925 2050);
FORCEPROP 2 LAST PATH I70
J 0
(-1855 2120);
DISPLAY 1.361702 (-1855 2120);
PAINT ORANGE (-1855 2120);
DISPLAY INVISIBLE (-1855 2120);
FORCEPROP 1 LAST OFFPAGE TRUE
J 0
(-1600 1925);
DISPLAY 0.893617 (-1600 1925);
PAINT GREEN (-1600 1925);
DISPLAY INVISIBLE (-1600 1925);
FORCEPROP 1 LAST COMMENT_BODY TRUE
J 0
(-1800 1950);
DISPLAY 0.893617 (-1800 1950);
PAINT GREEN (-1800 1950);
DISPLAY INVISIBLE (-1800 1950);
FORCEADD OFFPAGE..1
(-1925 2300);
FORCEPROP 2 LAST $XR0 223 
J 0
(-2177 2300);
DISPLAY 0.638298 (-2177 2300);
PAINT MONO (-2177 2300);
FORCEPROP 2 LAST CDS_LIB mstr_standard
J 0
(-1925 2300);
PAINT ORANGE (-1925 2300);
DISPLAY INVISIBLE (-1925 2300);
FORCEPROP 2 LAST PATH I72
J 0
(-1875 2375);
DISPLAY 1.361702 (-1875 2375);
PAINT ORANGE (-1875 2375);
DISPLAY INVISIBLE (-1875 2375);
FORCEPROP 1 LAST OFFPAGE TRUE
J 0
(-1600 2175);
DISPLAY 1.170213 (-1600 2175);
PAINT GREEN (-1600 2175);
DISPLAY INVISIBLE (-1600 2175);
FORCEPROP 1 LAST COMMENT_BODY TRUE
J 0
(-1800 2200);
DISPLAY 1.170213 (-1800 2200);
PAINT GREEN (-1800 2200);
DISPLAY INVISIBLE (-1800 2200);
FORCEADD PVDDQ_GHJ..1
(100 2450);
FORCEPROP 3 LASTPIN (100 2400) SIG_NAME PVDDQ_GHJ\g
J 0
(110 2410);
DISPLAY 0.659574 (110 2410);
PAINT MONO (110 2410);
DISPLAY INVISIBLE (110 2410);
FORCEPROP 1 LAST VOLTAGE 1.2V
J 0
(55 2407);
DISPLAY 0.340426 (55 2407);
PAINT SKYBLUE (55 2407);
DISPLAY INVISIBLE (55 2407);
FORCEPROP 2 LAST CDS_LIB mstr_symbols
J 0
(100 2450);
PAINT ORANGE (100 2450);
DISPLAY INVISIBLE (100 2450);
FORCEPROP 1 LAST PATH I73
J 0
(150 2475);
DISPLAY 0.872340 (150 2475);
PAINT AQUA (150 2475);
DISPLAY INVISIBLE (150 2475);
FORCEPROP 2 LAST BOM_COST MEM_VRD_PVPP_AB
J 0
(125 2550);
PAINT MONO (125 2550);
DISPLAY INVISIBLE (125 2550);
FORCEPROP 2 LAST ROOM VDDQ_GHJ_PWR_VR
J 0
(350 2550);
PAINT ORANGE (350 2550);
DISPLAY INVISIBLE (350 2550);
FORCEPROP 1 LAST BODY_TYPE PLUMBING
J 0
(55 2407);
DISPLAY 0.340426 (55 2407);
PAINT GREEN (55 2407);
DISPLAY INVISIBLE (55 2407);
FORCEPROP 1 LAST HDL_POWER PVDDQ_GHJ
J 1
(100 2500);
DISPLAY 0.872340 (100 2500);
PAINT GREEN (100 2500);
DISPLAY INVISIBLE (100 2500);
FORCEADD RES..2
(-650 2075);
FORCEPROP 1 LASTPIN (-650 1975) $PN 2
J 0
(-645 1985);
DISPLAY 0.617021 (-645 1985);
PAINT ORANGE (-645 1985);
FORCEPROP 1 LAST MATERIAL EMPTY
J 0
(-610 2000);
DISPLAY 0.617021 (-610 2000);
PAINT RED (-610 2000);
FORCEPROP 1 LASTPIN (-650 2175) $PN 1
J 0
(-645 2137);
DISPLAY 0.617021 (-645 2137);
PAINT ORANGE (-645 2137);
FORCEPROP 1 LAST TOLERANCE 1%
J 0
(-605 2100);
DISPLAY 0.617021 (-605 2100);
PAINT SKYBLUE (-605 2100);
FORCEPROP 1 LAST WATTAGE 1/16W
J 0
(-610 2050);
DISPLAY 0.617021 (-610 2050);
PAINT SKYBLUE (-610 2050);
FORCEPROP 1 LAST LOCATION R7U2
J 0
(-605 2200);
DISPLAY 0.617021 (-605 2200);
PAINT AQUA (-605 2200);
FORCEPROP 1 LAST VALUE 100.0
J 0
(-605 2150);
DISPLAY 0.617021 (-605 2150);
PAINT SKYBLUE (-605 2150);
FORCEPROP 1 LAST PART_NUMBER G21796-017
J 0
(-610 1950);
DISPLAY 0.617021 (-610 1950);
PAINT BLUE (-610 1950);
FORCEPROP 1 LAST PACK_TYPE 0402
J 0
(-610 1900);
DISPLAY 0.617021 (-610 1900);
PAINT SKYBLUE (-610 1900);
FORCEPROP 2 LAST CDS_LIB mstr_discrete
J 0
(-650 2075);
PAINT ORANGE (-650 2075);
DISPLAY INVISIBLE (-650 2075);
FORCEPROP 2 LAST CDS_LOCATION R7U2
J 0
(-605 2200);
DISPLAY 0.617021 (-605 2200);
PAINT AQUA (-605 2200);
DISPLAY INVISIBLE (-605 2200);
FORCEPROP 0 LAST ROOM VDDQ_GHJ_PWR_VR
J 0
(-600 2250);
DISPLAY 1.021277 (-600 2250);
PAINT ORANGE (-600 2250);
DISPLAY INVISIBLE (-600 2250);
FORCEPROP 1 LAST PATH I74
J 0
(-600 2250);
DISPLAY 1.319149 (-600 2250);
PAINT WHITE (-600 2250);
DISPLAY INVISIBLE (-600 2250);
FORCEPROP 2 LAST SEC_TYPE 0402
J 0
(-600 2325);
DISPLAY 1.021277 (-600 2325);
PAINT ORANGE (-600 2325);
DISPLAY INVISIBLE (-600 2325);
FORCEPROP 2 LAST SEC 1
J 0
(-600 2325);
DISPLAY 0.680851 (-600 2325);
PAINT MONO (-600 2325);
DISPLAY INVISIBLE (-600 2325);
FORCEADD CAPP..1
(3250 -50);
FORCEPROP 1 LAST PART_NUMBER 699013-049
J 0
(3300 -200);
DISPLAY 0.617021 (3300 -200);
PAINT BLUE (3300 -200);
FORCEPROP 0 LAST GROUP PWR_BULK_CAP
J 0
(3315 -249);
DISPLAY 0.638298 (3315 -249);
PAINT BROWN (3315 -249);
DISPLAY BOTH (3315 -249);
FORCEPROP 1 LASTPIN (3250 50) $PN 1
J 0
(3260 35);
DISPLAY 0.617021 (3260 35);
PAINT ORANGE (3260 35);
FORCEPROP 1 LASTPIN (3250 -150) $PN 2
J 0
(3260 -165);
DISPLAY 0.617021 (3260 -165);
PAINT ORANGE (3260 -165);
FORCEPROP 1 LAST LOCATION C9T5
J 0
(3300 100);
DISPLAY 0.617021 (3300 100);
PAINT AQUA (3300 100);
FORCEPROP 1 LAST VALUE 470UF
J 0
(3300 50);
DISPLAY 0.617021 (3300 50);
PAINT SKYBLUE (3300 50);
FORCEPROP 1 LAST MATERIAL ALUM
J 0
(3300 -100);
DISPLAY 0.617021 (3300 -100);
PAINT SKYBLUE (3300 -100);
FORCEPROP 1 LAST PACK_TYPE 3018
J 0
(3300 -150);
DISPLAY 0.617021 (3300 -150);
PAINT SKYBLUE (3300 -150);
FORCEPROP 1 LAST VOLTAGE 2.5V
J 0
(3300 -50);
DISPLAY 0.617021 (3300 -50);
PAINT SKYBLUE (3300 -50);
FORCEPROP 1 LAST TOLERANCE 20%
J 0
(3300 0);
DISPLAY 0.617021 (3300 0);
PAINT SKYBLUE (3300 0);
FORCEPROP 2 LAST SEC_TYPE 3018
J 0
(3300 175);
DISPLAY 1.021277 (3300 175);
PAINT ORANGE (3300 175);
DISPLAY INVISIBLE (3300 175);
FORCEPROP 2 LAST SEC 1
J 0
(3300 175);
DISPLAY 0.680851 (3300 175);
PAINT MONO (3300 175);
DISPLAY INVISIBLE (3300 175);
FORCEPROP 1 LAST PATH I75
J 0
(3300 100);
DISPLAY 1.319149 (3300 100);
PAINT ORANGE (3300 100);
DISPLAY INVISIBLE (3300 100);
FORCEPROP 0 LAST ROOM VDDQ_GHJ_PWR_VR
J 0
(3300 100);
DISPLAY 1.021277 (3300 100);
PAINT ORANGE (3300 100);
DISPLAY INVISIBLE (3300 100);
FORCEPROP 2 LAST CDS_LOCATION C9T5
J 0
(3300 50);
DISPLAY 0.617021 (3300 50);
PAINT AQUA (3300 50);
DISPLAY INVISIBLE (3300 50);
FORCEPROP 2 LAST CDS_LIB mstr_discrete
J 0
(3250 -50);
PAINT ORANGE (3250 -50);
DISPLAY INVISIBLE (3250 -50);
FORCEADD CAPP..1
(3550 -50);
FORCEPROP 1 LAST LOCATION C9U2
J 0
(3600 100);
DISPLAY 0.617021 (3600 100);
PAINT AQUA (3600 100);
FORCEPROP 0 LAST GROUP PWR_BULK_CAP
J 0
(3615 -299);
DISPLAY 0.638298 (3615 -299);
PAINT BROWN (3615 -299);
DISPLAY BOTH (3615 -299);
FORCEPROP 1 LAST VOLTAGE 2.5V
J 0
(3600 -50);
DISPLAY 0.617021 (3600 -50);
PAINT SKYBLUE (3600 -50);
FORCEPROP 1 LAST MATERIAL ALUM
J 0
(3600 -100);
DISPLAY 0.617021 (3600 -100);
PAINT SKYBLUE (3600 -100);
FORCEPROP 1 LAST PART_NUMBER 699013-049
J 0
(3600 -200);
DISPLAY 0.617021 (3600 -200);
PAINT BLUE (3600 -200);
FORCEPROP 1 LAST PACK_TYPE 3018
J 0
(3600 -150);
DISPLAY 0.617021 (3600 -150);
PAINT SKYBLUE (3600 -150);
FORCEPROP 1 LASTPIN (3550 50) $PN 1
J 0
(3560 35);
DISPLAY 0.617021 (3560 35);
PAINT ORANGE (3560 35);
FORCEPROP 1 LASTPIN (3550 -150) $PN 2
J 0
(3560 -165);
DISPLAY 0.617021 (3560 -165);
PAINT ORANGE (3560 -165);
FORCEPROP 1 LAST TOLERANCE 20%
J 0
(3600 0);
DISPLAY 0.617021 (3600 0);
PAINT SKYBLUE (3600 0);
FORCEPROP 1 LAST VALUE 470UF
J 0
(3600 50);
DISPLAY 0.617021 (3600 50);
PAINT SKYBLUE (3600 50);
FORCEPROP 2 LAST SEC_TYPE 3018
J 0
(3600 175);
DISPLAY 1.021277 (3600 175);
PAINT ORANGE (3600 175);
DISPLAY INVISIBLE (3600 175);
FORCEPROP 2 LAST SEC 1
J 0
(3600 175);
DISPLAY 0.680851 (3600 175);
PAINT MONO (3600 175);
DISPLAY INVISIBLE (3600 175);
FORCEPROP 2 LAST CDS_LOCATION C9U2
J 0
(3600 50);
DISPLAY 0.617021 (3600 50);
PAINT AQUA (3600 50);
DISPLAY INVISIBLE (3600 50);
FORCEPROP 1 LAST PATH I76
J 0
(3600 100);
DISPLAY 1.319149 (3600 100);
PAINT ORANGE (3600 100);
DISPLAY INVISIBLE (3600 100);
FORCEPROP 0 LAST ROOM VDDQ_GHJ_PWR_VR
J 0
(3600 100);
DISPLAY 1.021277 (3600 100);
PAINT ORANGE (3600 100);
DISPLAY INVISIBLE (3600 100);
FORCEPROP 2 LAST CDS_LIB mstr_discrete
J 0
(3550 -50);
PAINT ORANGE (3550 -50);
DISPLAY INVISIBLE (3550 -50);
FORCEADD CAPP..1
(3850 -50);
FORCEPROP 1 LAST VALUE 470UF
J 0
(3900 50);
DISPLAY 0.617021 (3900 50);
PAINT SKYBLUE (3900 50);
FORCEPROP 0 LAST GROUP PWR_BULK_CAP
J 0
(3915 -249);
DISPLAY 0.638298 (3915 -249);
PAINT BROWN (3915 -249);
DISPLAY BOTH (3915 -249);
FORCEPROP 1 LASTPIN (3850 -150) $PN 2
J 0
(3860 -165);
DISPLAY 0.617021 (3860 -165);
PAINT ORANGE (3860 -165);
FORCEPROP 1 LASTPIN (3850 50) $PN 1
J 0
(3860 35);
DISPLAY 0.617021 (3860 35);
PAINT ORANGE (3860 35);
FORCEPROP 1 LAST LOCATION C9U9
J 0
(3900 100);
DISPLAY 0.617021 (3900 100);
PAINT AQUA (3900 100);
FORCEPROP 1 LAST PART_NUMBER 699013-049
J 0
(3900 -200);
DISPLAY 0.617021 (3900 -200);
PAINT BLUE (3900 -200);
FORCEPROP 1 LAST PACK_TYPE 3018
J 0
(3900 -150);
DISPLAY 0.617021 (3900 -150);
PAINT SKYBLUE (3900 -150);
FORCEPROP 1 LAST MATERIAL ALUM
J 0
(3900 -100);
DISPLAY 0.617021 (3900 -100);
PAINT SKYBLUE (3900 -100);
FORCEPROP 1 LAST TOLERANCE 20%
J 0
(3900 0);
DISPLAY 0.617021 (3900 0);
PAINT SKYBLUE (3900 0);
FORCEPROP 1 LAST VOLTAGE 2.5V
J 0
(3900 -50);
DISPLAY 0.617021 (3900 -50);
PAINT SKYBLUE (3900 -50);
FORCEPROP 2 LAST CDS_LIB mstr_discrete
J 0
(3850 -50);
PAINT ORANGE (3850 -50);
DISPLAY INVISIBLE (3850 -50);
FORCEPROP 2 LAST SEC_TYPE 3018
J 0
(3900 175);
DISPLAY 1.021277 (3900 175);
PAINT ORANGE (3900 175);
DISPLAY INVISIBLE (3900 175);
FORCEPROP 2 LAST SEC 1
J 0
(3900 175);
DISPLAY 0.680851 (3900 175);
PAINT MONO (3900 175);
DISPLAY INVISIBLE (3900 175);
FORCEPROP 2 LAST CDS_LOCATION C9U9
J 0
(3900 50);
DISPLAY 0.617021 (3900 50);
PAINT AQUA (3900 50);
DISPLAY INVISIBLE (3900 50);
FORCEPROP 1 LAST PATH I77
J 0
(3900 100);
DISPLAY 1.319149 (3900 100);
PAINT ORANGE (3900 100);
DISPLAY INVISIBLE (3900 100);
FORCEPROP 0 LAST ROOM VDDQ_GHJ_PWR_VR
J 0
(3900 100);
DISPLAY 1.021277 (3900 100);
PAINT ORANGE (3900 100);
DISPLAY INVISIBLE (3900 100);
FORCEADD CAPP..1
(4150 -50);
FORCEPROP 0 LAST GROUP PWR_BULK_CAP
J 0
(4215 -299);
DISPLAY 0.638298 (4215 -299);
PAINT BROWN (4215 -299);
DISPLAY BOTH (4215 -299);
FORCEPROP 1 LAST PART_NUMBER 699013-049
J 0
(4200 -200);
DISPLAY 0.617021 (4200 -200);
PAINT BLUE (4200 -200);
FORCEPROP 1 LASTPIN (4150 -150) $PN 2
J 0
(4160 -165);
DISPLAY 0.617021 (4160 -165);
PAINT ORANGE (4160 -165);
FORCEPROP 1 LASTPIN (4150 50) $PN 1
J 0
(4160 35);
DISPLAY 0.617021 (4160 35);
PAINT ORANGE (4160 35);
FORCEPROP 1 LAST PACK_TYPE 3018
J 0
(4200 -150);
DISPLAY 0.617021 (4200 -150);
PAINT SKYBLUE (4200 -150);
FORCEPROP 1 LAST MATERIAL ALUM
J 0
(4200 -100);
DISPLAY 0.617021 (4200 -100);
PAINT SKYBLUE (4200 -100);
FORCEPROP 1 LAST VOLTAGE 2.5V
J 0
(4200 -50);
DISPLAY 0.617021 (4200 -50);
PAINT SKYBLUE (4200 -50);
FORCEPROP 1 LAST TOLERANCE 20%
J 0
(4200 0);
DISPLAY 0.617021 (4200 0);
PAINT SKYBLUE (4200 0);
FORCEPROP 1 LAST LOCATION C9U5
J 0
(4200 100);
DISPLAY 0.617021 (4200 100);
PAINT AQUA (4200 100);
FORCEPROP 1 LAST VALUE 470UF
J 0
(4200 50);
DISPLAY 0.617021 (4200 50);
PAINT SKYBLUE (4200 50);
FORCEPROP 2 LAST CDS_LIB mstr_discrete
J 0
(4150 -50);
PAINT ORANGE (4150 -50);
DISPLAY INVISIBLE (4150 -50);
FORCEPROP 2 LAST CDS_LOCATION C9U5
J 0
(4200 50);
DISPLAY 0.617021 (4200 50);
PAINT AQUA (4200 50);
DISPLAY INVISIBLE (4200 50);
FORCEPROP 2 LAST SEC_TYPE 3018
J 0
(4200 175);
DISPLAY 1.021277 (4200 175);
PAINT ORANGE (4200 175);
DISPLAY INVISIBLE (4200 175);
FORCEPROP 2 LAST SEC 1
J 0
(4200 175);
DISPLAY 0.680851 (4200 175);
PAINT MONO (4200 175);
DISPLAY INVISIBLE (4200 175);
FORCEPROP 1 LAST PATH I78
J 0
(4200 100);
DISPLAY 1.319149 (4200 100);
PAINT ORANGE (4200 100);
DISPLAY INVISIBLE (4200 100);
FORCEPROP 0 LAST ROOM VDDQ_GHJ_PWR_VR
J 0
(4200 100);
DISPLAY 1.021277 (4200 100);
PAINT ORANGE (4200 100);
DISPLAY INVISIBLE (4200 100);
FORCEADD PVDDQ_GHJ..1
(3250 250);
FORCEPROP 3 LASTPIN (3250 200) SIG_NAME PVDDQ_GHJ\g
J 0
(3260 210);
DISPLAY 0.659574 (3260 210);
PAINT MONO (3260 210);
DISPLAY INVISIBLE (3260 210);
FORCEPROP 2 LAST ROOM VDDQ_GHJ_PWR_VR
J 0
(3475 350);
PAINT ORANGE (3475 350);
DISPLAY INVISIBLE (3475 350);
FORCEPROP 2 LAST BOM_COST MEM_VRD_PVPP_AB
J 0
(3300 350);
PAINT MONO (3300 350);
DISPLAY INVISIBLE (3300 350);
FORCEPROP 1 LAST PATH I80
J 0
(3300 275);
DISPLAY 0.872340 (3300 275);
PAINT AQUA (3300 275);
DISPLAY INVISIBLE (3300 275);
FORCEPROP 2 LAST CDS_LIB mstr_symbols
J 0
(3250 250);
PAINT ORANGE (3250 250);
DISPLAY INVISIBLE (3250 250);
FORCEPROP 1 LAST VOLTAGE 1.2V
J 0
(3205 207);
DISPLAY 0.340426 (3205 207);
PAINT SKYBLUE (3205 207);
DISPLAY INVISIBLE (3205 207);
FORCEPROP 1 LAST BODY_TYPE PLUMBING
J 0
(3205 207);
DISPLAY 0.340426 (3205 207);
PAINT GREEN (3205 207);
DISPLAY INVISIBLE (3205 207);
FORCEPROP 1 LAST HDL_POWER PVDDQ_GHJ
J 1
(3250 300);
DISPLAY 0.872340 (3250 300);
PAINT GREEN (3250 300);
DISPLAY INVISIBLE (3250 300);
FORCEADD GND..1
(3250 -375);
FORCEPROP 3 LASTPIN (3250 -325) SIG_NAME GND\g
J 0
(3260 -315);
DISPLAY 0.659574 (3260 -315);
PAINT MONO (3260 -315);
DISPLAY INVISIBLE (3260 -315);
FORCEPROP 2 LAST BOM_COST MEM_VRD_PVPP_AB
J 0
(2925 -300);
PAINT MONO (2925 -300);
DISPLAY INVISIBLE (2925 -300);
FORCEPROP 1 LAST SIZE 1B
J 0
(3325 -425);
DISPLAY 0.893617 (3325 -425);
PAINT GREEN (3325 -425);
DISPLAY INVISIBLE (3325 -425);
FORCEPROP 1 LAST PATH I81
J 0
(3325 -375);
DISPLAY 1.170213 (3325 -375);
PAINT AQUA (3325 -375);
DISPLAY INVISIBLE (3325 -375);
FORCEPROP 2 LAST CDS_LIB mstr_symbols
J 0
(3250 -375);
PAINT ORANGE (3250 -375);
DISPLAY INVISIBLE (3250 -375);
FORCEPROP 1 LAST VOLTAGE 0
J 0
(3250 -375);
PAINT SKYBLUE (3250 -375);
DISPLAY INVISIBLE (3250 -375);
FORCEPROP 1 LAST BODY_TYPE PLUMBING
J 0
(3205 -418);
DISPLAY 0.340426 (3205 -418);
PAINT GREEN (3205 -418);
DISPLAY INVISIBLE (3205 -418);
FORCEPROP 1 LAST HDL_POWER GND
J 0
(3250 -225);
DISPLAY 0.893617 (3250 -225);
PAINT GREEN (3250 -225);
DISPLAY INVISIBLE (3250 -225);
FORCEADD PVDDQ_GHJ..1
(2400 3100);
FORCEPROP 3 LASTPIN (2400 3050) SIG_NAME PVDDQ_GHJ\g
J 0
(2410 3060);
DISPLAY 0.659574 (2410 3060);
PAINT MONO (2410 3060);
DISPLAY INVISIBLE (2410 3060);
FORCEPROP 1 LAST VOLTAGE 1.2V
J 0
(2355 3057);
DISPLAY 0.340426 (2355 3057);
PAINT SKYBLUE (2355 3057);
DISPLAY INVISIBLE (2355 3057);
FORCEPROP 2 LAST BOM_COST MEM_VRD_PVDDQ_CD
J 0
(2475 3200);
PAINT MONO (2475 3200);
DISPLAY INVISIBLE (2475 3200);
FORCEPROP 2 LAST CDS_LIB mstr_symbols
J 0
(2400 3100);
PAINT ORANGE (2400 3100);
DISPLAY INVISIBLE (2400 3100);
FORCEPROP 1 LAST PATH I93
J 0
(2450 3125);
DISPLAY 0.872340 (2450 3125);
PAINT AQUA (2450 3125);
DISPLAY INVISIBLE (2450 3125);
FORCEPROP 2 LAST ROOM VDDQ_GHJ_PWR_VR
J 0
(2650 3200);
PAINT ORANGE (2650 3200);
DISPLAY INVISIBLE (2650 3200);
FORCEPROP 1 LAST BODY_TYPE PLUMBING
J 0
(2355 3057);
DISPLAY 0.340426 (2355 3057);
PAINT GREEN (2355 3057);
DISPLAY INVISIBLE (2355 3057);
FORCEPROP 1 LAST HDL_POWER PVDDQ_GHJ
J 1
(2400 3150);
DISPLAY 0.872340 (2400 3150);
PAINT GREEN (2400 3150);
DISPLAY INVISIBLE (2400 3150);
FORCEADD GND..1
(2400 2350);
FORCEPROP 3 LASTPIN (2400 2400) SIG_NAME GND\g
J 0
(2410 2410);
DISPLAY 0.659574 (2410 2410);
PAINT MONO (2410 2410);
DISPLAY INVISIBLE (2410 2410);
FORCEPROP 1 LAST PATH I94
J 0
(2475 2350);
DISPLAY 1.170213 (2475 2350);
PAINT AQUA (2475 2350);
DISPLAY INVISIBLE (2475 2350);
FORCEPROP 1 LAST SIZE 1B
J 0
(2475 2300);
DISPLAY 0.893617 (2475 2300);
PAINT GREEN (2475 2300);
DISPLAY INVISIBLE (2475 2300);
FORCEPROP 2 LAST CDS_LIB mstr_symbols
J 0
(2400 2350);
PAINT ORANGE (2400 2350);
DISPLAY INVISIBLE (2400 2350);
FORCEPROP 1 LAST VOLTAGE 0
J 0
(2400 2350);
PAINT SKYBLUE (2400 2350);
DISPLAY INVISIBLE (2400 2350);
FORCEPROP 2 LAST BOM_COST MEM_VRD_PVDDQ_CD
J 0
(2075 2425);
PAINT MONO (2075 2425);
DISPLAY INVISIBLE (2075 2425);
FORCEPROP 2 LAST ROOM VDDQ_GHJ_PWR_VR
J 0
(1850 2425);
PAINT ORANGE (1850 2425);
DISPLAY INVISIBLE (1850 2425);
FORCEPROP 1 LAST BODY_TYPE PLUMBING
J 0
(2355 2307);
DISPLAY 0.340426 (2355 2307);
PAINT GREEN (2355 2307);
DISPLAY INVISIBLE (2355 2307);
FORCEPROP 1 LAST HDL_POWER GND
J 0
(2400 2500);
DISPLAY 0.893617 (2400 2500);
PAINT GREEN (2400 2500);
DISPLAY INVISIBLE (2400 2500);
FORCEADD DNS..3
(-270 1870);
PAINT RED (-270 1870);
FORCEPROP 2 LAST CDS_LIB mstr_misc
J 0
(-270 1870);
PAINT ORANGE (-270 1870);
DISPLAY INVISIBLE (-270 1870);
FORCEPROP 1 LAST COMMENT_BODY TRUE
R 1
J 0
(-195 1645);
DISPLAY 0.872340 (-195 1645);
PAINT GREEN (-195 1645);
DISPLAY INVISIBLE (-195 1645);
FORCEADD DNS..3
(-245 2320);
PAINT RED (-245 2320);
FORCEPROP 2 LAST CDS_LIB mstr_misc
J 0
(-245 2320);
PAINT ORANGE (-245 2320);
DISPLAY INVISIBLE (-245 2320);
FORCEPROP 1 LAST COMMENT_BODY TRUE
R 1
J 0
(-170 2095);
DISPLAY 0.872340 (-170 2095);
PAINT GREEN (-170 2095);
DISPLAY INVISIBLE (-170 2095);
FORCEADD DNS..2
(-645 2070);
PAINT RED (-645 2070);
FORCEPROP 2 LAST CDS_LIB mstr_misc
J 0
(-645 2070);
PAINT ORANGE (-645 2070);
DISPLAY INVISIBLE (-645 2070);
FORCEPROP 1 LAST COMMENT_BODY TRUE
R 1
J 0
(-570 1845);
DISPLAY 0.872340 (-570 1845);
PAINT GREEN (-570 1845);
DISPLAY INVISIBLE (-570 1845);
FORCEADD INTEL_CORP_BPAGE..1
(5475 -1450);
FORCEPROP 1 LAST CDS_CON_LAST_MODIFIED Fri Jun 16 17:49:21 2017
J 0
(4050 -1125);
PAINT GREEN (4050 -1125);
DISPLAY INVISIBLE (4050 -1125);
FORCEPROP 2 LAST CUSTOM_TXT_CDS <XR_PAGE_TITLE>
J 0
(-2415 3800);
DISPLAY 0.638298 (-2415 3800);
PAINT PINK (-2415 3800);
DISPLAY INVISIBLE (-2415 3800);
FORCEPROP 2 LAST CUSTOM_TXT_CDS <CON_LAST_MODIFIED>
J 0
(1475 -1350);
PAINT ORANGE (1475 -1350);
FORCEPROP 2 LAST CUSTOM_TXT_CDS <CON_PAGE_NUM> OF <CON_TOTAL_PAGES>
J 0
(4975 -1425);
PAINT GREEN (4975 -1425);
FORCEPROP 2 LAST CUSTOM_TXT_CDS <CURRENT_DESIGN_SHEET> OF <TOTAL_DESIGN_SHEETS>
J 0
(4975 -1425);
PAINT ORANGE (4975 -1425);
FORCEPROP 1 LAST SCH_TITLE VDDQ GHJ DECAP (3 OF 3)
J 0
(-2475 -1400);
DISPLAY 1.212766 (-2475 -1400);
PAINT GREEN (-2475 -1400);
FORCEPROP 2 LAST CDS_LIB mstr_symbols
J 0
(5475 -1450);
PAINT ORANGE (5475 -1450);
DISPLAY INVISIBLE (5475 -1450);
FORCEPROP 2 LAST PAGE_BORDER TRUE
J 0
(-2415 3800);
DISPLAY 0.851064 (-2415 3800);
PAINT PINK (-2415 3800);
DISPLAY INVISIBLE (-2415 3800);
FORCEPROP 2 LAST ROOM VDDQ_GHJ_PWR_VR
J 0
(-2625 3650);
PAINT ORANGE (-2625 3650);
DISPLAY INVISIBLE (-2625 3650);
FORCEPROP 1 LAST COMMENT_BODY TRUE
J 0
(5487 -1438);
DISPLAY 0.446809 (5487 -1438);
PAINT GREEN (5487 -1438);
DISPLAY INVISIBLE (5487 -1438);
FORCEPROP 2 LAST CDS_XR_PAGE_TITLE CR-225 : @BASEBOARD_FAB2_LIB.BASEBOARD_FAB2(SCH_1):PAGE225
J 0
(-2415 3800);
DISPLAY 0.638298 (-2415 3800);
PAINT PINK (-2415 3800);
DISPLAY INVISIBLE (-2415 3800);
WIRE 16 -1 (2550 1900)(2550 1950);
WIRE 16 -1 (2550 1900)(2900 1900);
WIRE 16 -1 (2550 1900)(2550 1825);
WIRE 16 -1 (3300 1900)(2900 1900);
WIRE 16 -1 (2900 1825)(2900 1900);
WIRE 16 -1 (3650 1900)(3300 1900);
WIRE 16 -1 (3300 1825)(3300 1900);
WIRE 16 -1 (4000 1900)(3650 1900);
WIRE 16 -1 (3650 1825)(3650 1900);
WIRE 16 -1 (4400 1900)(4000 1900);
WIRE 16 -1 (4000 1825)(4000 1900);
WIRE 16 -1 (4400 1825)(4400 1900);
WIRE 16 -1 (4275 1400)(4275 1475);
WIRE 16 -1 (4275 1475)(4000 1475);
WIRE 16 -1 (4275 1475)(4400 1475);
WIRE 16 -1 (4400 1625)(4400 1475);
WIRE 16 -1 (3650 1475)(4000 1475);
WIRE 16 -1 (4000 1625)(4000 1475);
WIRE 16 -1 (3300 1475)(3650 1475);
WIRE 16 -1 (3650 1625)(3650 1475);
WIRE 16 -1 (2900 1475)(3300 1475);
WIRE 16 -1 (3300 1625)(3300 1475);
WIRE 16 -1 (2550 1475)(2900 1475);
WIRE 16 -1 (2900 1625)(2900 1475);
WIRE 16 -1 (2550 1625)(2550 1475);
WIRE 16 -1 (-1250 1525)(-1250 1350);
WIRE 16 -1 (-1250 1350)(-950 1350);
WIRE 16 -1 (-1600 1350)(-1250 1350);
WIRE 16 -1 (-1250 1225)(-1250 1350);
WIRE 16 -1 (-550 1350)(-950 1350);
WIRE 16 -1 (-950 1350)(-950 1225);
WIRE 16 -1 (-550 1350)(-250 1350);
WIRE 16 -1 (-550 1350)(-550 1225);
WIRE 16 -1 (150 1350)(-250 1350);
WIRE 16 -1 (-250 1350)(-250 1225);
WIRE 16 -1 (150 1350)(450 1350);
WIRE 16 -1 (150 1350)(150 1225);
WIRE 16 -1 (850 1350)(450 1350);
WIRE 16 -1 (450 1350)(450 1225);
WIRE 16 -1 (1150 1350)(850 1350);
WIRE 16 -1 (850 1350)(850 1225);
WIRE 16 -1 (1150 1350)(1150 1225);
WIRE 16 -1 (-1250 950)(-1250 925);
WIRE 16 -1 (-1250 950)(-950 950);
WIRE 16 -1 (-1250 1075)(-1250 950);
WIRE 16 -1 (-550 950)(-950 950);
WIRE 16 -1 (-950 1075)(-950 950);
WIRE 16 -1 (-550 950)(-250 950);
WIRE 16 -1 (-550 950)(-550 1075);
WIRE 16 -1 (150 950)(-250 950);
WIRE 16 -1 (-250 1075)(-250 950);
WIRE 16 -1 (150 950)(450 950);
WIRE 16 -1 (150 950)(150 1075);
WIRE 16 -1 (850 950)(450 950);
WIRE 16 -1 (450 1075)(450 950);
WIRE 16 -1 (1150 950)(850 950);
WIRE 16 -1 (850 950)(850 1075);
WIRE 16 -1 (1150 1075)(1150 950);
WIRE 16 -1 (-2025 1350)(-2025 1500);
WIRE 16 -1 (-2025 1350)(-1900 1350);
WIRE 16 -1 (-350 2775)(-350 2850);
WIRE 16 -1 (-750 2850)(-350 2850);
WIRE 16 -1 (-350 3000)(-350 2850);
WIRE 16 -1 (-1100 2850)(-750 2850);
WIRE 16 -1 (-750 3000)(-750 2850);
WIRE 16 -1 (-1450 2850)(-1100 2850);
WIRE 16 -1 (-1100 3000)(-1100 2850);
WIRE 16 -1 (-1450 3000)(-1450 2850);
WIRE 16 -1 (-2325 3275)(-2325 3325);
WIRE 16 -1 (-2325 3275)(-1975 3275);
WIRE 16 -1 (-2325 3275)(-2325 3200);
WIRE 16 -1 (-1975 3200)(-1975 3275);
WIRE 16 -1 (2600 1150)(2600 1200);
WIRE 16 -1 (2600 1150)(2950 1150);
WIRE 16 -1 (2600 1150)(2600 1075);
WIRE 16 -1 (3350 1150)(2950 1150);
WIRE 16 -1 (2950 1075)(2950 1150);
WIRE 16 -1 (3350 1075)(3350 1150);
WIRE 16 -1 (3425 625)(3425 725);
WIRE 16 -1 (3350 725)(3425 725);
WIRE 16 -1 (2950 725)(3350 725);
WIRE 16 -1 (3350 875)(3350 725);
WIRE 16 -1 (2600 725)(2950 725);
WIRE 16 -1 (2950 875)(2950 725);
WIRE 16 -1 (2600 875)(2600 725);
WIRE 16 -1 (-1450 3275)(-1450 3325);
WIRE 16 -1 (-1100 3275)(-1450 3275);
WIRE 16 -1 (-1450 3200)(-1450 3275);
WIRE 16 -1 (-750 3275)(-1100 3275);
WIRE 16 -1 (-1100 3200)(-1100 3275);
WIRE 16 -1 (-350 3275)(-750 3275);
WIRE 16 -1 (-750 3200)(-750 3275);
WIRE 16 -1 (-350 3200)(-350 3275);
WIRE 16 -1 (-2325 2675)(-2325 2700);
WIRE 16 -1 (-2325 2700)(-1975 2700);
WIRE 16 -1 (-2325 3000)(-2325 2700);
WIRE 16 -1 (-1975 3000)(-1975 2700);
WIRE 16 -1 (-2275 400)(-2275 450);
WIRE 16 -1 (-2275 400)(-1975 400);
WIRE 16 -1 (-2275 350)(-2275 400);
WIRE 16 -1 (-1975 400)(-1675 400);
WIRE 16 -1 (-1975 350)(-1975 400);
WIRE 16 -1 (-1675 400)(-1400 400);
WIRE 16 -1 (-1675 350)(-1675 400);
WIRE 16 -1 (-1125 400)(-1400 400);
WIRE 16 -1 (-1400 350)(-1400 400);
WIRE 16 -1 (-825 400)(-1125 400);
WIRE 16 -1 (-1125 350)(-1125 400);
WIRE 16 -1 (-525 400)(-825 400);
WIRE 16 -1 (-825 350)(-825 400);
WIRE 16 -1 (-250 400)(-525 400);
WIRE 16 -1 (-525 350)(-525 400);
WIRE 16 -1 (75 400)(-250 400);
WIRE 16 -1 (-250 350)(-250 400);
WIRE 16 -1 (375 400)(75 400);
WIRE 16 -1 (75 350)(75 400);
WIRE 16 -1 (675 400)(375 400);
WIRE 16 -1 (375 350)(375 400);
WIRE 16 -1 (950 400)(675 400);
WIRE 16 -1 (675 350)(675 400);
WIRE 16 -1 (1225 400)(950 400);
WIRE 16 -1 (950 350)(950 400);
WIRE 16 -1 (1525 400)(1225 400);
WIRE 16 -1 (1225 350)(1225 400);
WIRE 16 -1 (1825 400)(1525 400);
WIRE 16 -1 (1525 350)(1525 400);
WIRE 16 -1 (2100 400)(1825 400);
WIRE 16 -1 (1825 350)(1825 400);
WIRE 16 -1 (2100 350)(2100 400);
WIRE 16 -1 (-2275 25)(-2275 -25);
WIRE 16 -1 (-1975 25)(-2275 25);
WIRE 16 -1 (-2275 150)(-2275 25);
WIRE 16 -1 (-1675 25)(-1975 25);
WIRE 16 -1 (-1975 150)(-1975 25);
WIRE 16 -1 (-1675 25)(-1400 25);
WIRE 16 -1 (-1675 150)(-1675 25);
WIRE 16 -1 (-1125 25)(-1400 25);
WIRE 16 -1 (-1400 150)(-1400 25);
WIRE 16 -1 (-825 25)(-1125 25);
WIRE 16 -1 (-1125 150)(-1125 25);
WIRE 16 -1 (-525 25)(-825 25);
WIRE 16 -1 (-825 150)(-825 25);
WIRE 16 -1 (-250 25)(-525 25);
WIRE 16 -1 (-525 150)(-525 25);
WIRE 16 -1 (75 25)(-250 25);
WIRE 16 -1 (-250 150)(-250 25);
WIRE 16 -1 (375 25)(75 25);
WIRE 16 -1 (75 150)(75 25);
WIRE 16 -1 (675 25)(375 25);
WIRE 16 -1 (375 150)(375 25);
WIRE 16 -1 (950 25)(675 25);
WIRE 16 -1 (675 150)(675 25);
WIRE 16 -1 (1225 25)(950 25);
WIRE 16 -1 (950 150)(950 25);
WIRE 16 -1 (1525 25)(1225 25);
WIRE 16 -1 (1225 150)(1225 25);
WIRE 16 -1 (1825 25)(1525 25);
WIRE 16 -1 (1525 150)(1525 25);
WIRE 16 -1 (2100 25)(1825 25);
WIRE 16 -1 (1825 150)(1825 25);
WIRE 16 -1 (2100 150)(2100 25);
WIRE 16 -1 (-2250 -300)(-2250 -250);
WIRE 16 -1 (-2250 -300)(-1950 -300);
WIRE 16 -1 (-2250 -350)(-2250 -300);
WIRE 16 -1 (-1950 -300)(-1650 -300);
WIRE 16 -1 (-1950 -350)(-1950 -300);
WIRE 16 -1 (-1650 -300)(-1375 -300);
WIRE 16 -1 (-1650 -350)(-1650 -300);
WIRE 16 -1 (-1100 -300)(-1375 -300);
WIRE 16 -1 (-1375 -350)(-1375 -300);
WIRE 16 -1 (-800 -300)(-1100 -300);
WIRE 16 -1 (-1100 -350)(-1100 -300);
WIRE 16 -1 (-500 -300)(-800 -300);
WIRE 16 -1 (-800 -350)(-800 -300);
WIRE 16 -1 (-225 -300)(-500 -300);
WIRE 16 -1 (-500 -350)(-500 -300);
WIRE 16 -1 (100 -300)(-225 -300);
WIRE 16 -1 (-225 -350)(-225 -300);
WIRE 16 -1 (400 -300)(100 -300);
WIRE 16 -1 (100 -350)(100 -300);
WIRE 16 -1 (700 -300)(400 -300);
WIRE 16 -1 (400 -350)(400 -300);
WIRE 16 -1 (975 -300)(700 -300);
WIRE 16 -1 (700 -350)(700 -300);
WIRE 16 -1 (1250 -300)(975 -300);
WIRE 16 -1 (975 -350)(975 -300);
WIRE 16 -1 (1550 -300)(1250 -300);
WIRE 16 -1 (1250 -350)(1250 -300);
WIRE 16 -1 (1850 -300)(1550 -300);
WIRE 16 -1 (1550 -350)(1550 -300);
WIRE 16 -1 (2125 -300)(1850 -300);
WIRE 16 -1 (1850 -350)(1850 -300);
WIRE 16 -1 (2125 -350)(2125 -300);
WIRE 16 -1 (-2250 -700)(-2250 -750);
WIRE 16 -1 (-1950 -700)(-2250 -700);
WIRE 16 -1 (-2250 -550)(-2250 -700);
WIRE 16 -1 (-1650 -700)(-1950 -700);
WIRE 16 -1 (-1950 -550)(-1950 -700);
WIRE 16 -1 (-1650 -700)(-1375 -700);
WIRE 16 -1 (-1650 -550)(-1650 -700);
WIRE 16 -1 (-1100 -700)(-1375 -700);
WIRE 16 -1 (-1375 -550)(-1375 -700);
WIRE 16 -1 (-800 -700)(-1100 -700);
WIRE 16 -1 (-1100 -550)(-1100 -700);
WIRE 16 -1 (-500 -700)(-800 -700);
WIRE 16 -1 (-800 -550)(-800 -700);
WIRE 16 -1 (-225 -700)(-500 -700);
WIRE 16 -1 (-500 -550)(-500 -700);
WIRE 16 -1 (100 -700)(-225 -700);
WIRE 16 -1 (-225 -550)(-225 -700);
WIRE 16 -1 (400 -700)(100 -700);
WIRE 16 -1 (100 -550)(100 -700);
WIRE 16 -1 (700 -700)(400 -700);
WIRE 16 -1 (400 -550)(400 -700);
WIRE 16 -1 (975 -700)(700 -700);
WIRE 16 -1 (700 -550)(700 -700);
WIRE 16 -1 (1250 -700)(975 -700);
WIRE 16 -1 (975 -550)(975 -700);
WIRE 16 -1 (1550 -700)(1250 -700);
WIRE 16 -1 (1250 -550)(1250 -700);
WIRE 16 -1 (1850 -700)(1550 -700);
WIRE 16 -1 (1550 -550)(1550 -700);
WIRE 16 -1 (2125 -700)(1850 -700);
WIRE 16 -1 (1850 -550)(1850 -700);
WIRE 16 -1 (2125 -550)(2125 -700);
WIRE 16 -1 (100 3200)(100 3300);
WIRE 16 -1 (100 3200)(450 3200);
WIRE 16 -1 (100 3125)(100 3200);
WIRE 16 -1 (450 3200)(800 3200);
WIRE 16 -1 (450 3125)(450 3200);
WIRE 16 -1 (800 3200)(800 3125);
WIRE 16 -1 (100 2625)(100 2650);
WIRE 16 -1 (100 2650)(450 2650);
WIRE 16 -1 (100 2925)(100 2650);
WIRE 16 -1 (450 2650)(800 2650);
WIRE 16 -1 (450 2925)(450 2650);
WIRE 16 -1 (800 2650)(800 2925);
WIRE 16 -1 (1600 1850)(1600 1800);
WIRE 16 -1 (1300 1850)(1600 1850);
WIRE 16 -1 (1600 1850)(1600 2000);
WIRE 16 -1 (1000 1850)(1300 1850);
WIRE 16 -1 (1300 2000)(1300 1850);
WIRE 16 -1 (700 1850)(1000 1850);
WIRE 16 -1 (1000 2000)(1000 1850);
WIRE 16 -1 (700 2000)(700 1850);
WIRE 16 -1 (700 2300)(700 2250);
WIRE 16 -1 (700 2250)(1000 2250);
WIRE 16 -1 (700 2200)(700 2250);
WIRE 16 -1 (1000 2250)(1300 2250);
WIRE 16 -1 (1000 2250)(1000 2200);
WIRE 16 -1 (1300 2250)(1600 2250);
WIRE 16 -1 (1300 2250)(1300 2200);
WIRE 16 -1 (1600 2250)(1600 2200);
WIRE 16 -1 (1625 2900)(1625 2950);
WIRE 16 -1 (1625 3225)(1625 3150);
WIRE 16 -1 (100 1800)(100 1875);
WIRE 16 -1 (100 1875)(-125 1875);
WIRE 16 -1 (100 2400)(100 2325);
WIRE 16 -1 (100 2325)(-100 2325);
WIRE 16 -1 (3250 150)(3250 200);
WIRE 16 -1 (3250 150)(3550 150);
WIRE 16 -1 (3250 50)(3250 150);
WIRE 16 -1 (3850 150)(3550 150);
WIRE 16 -1 (3550 50)(3550 150);
WIRE 16 -1 (4150 150)(3850 150);
WIRE 16 -1 (3850 50)(3850 150);
WIRE 16 -1 (4450 150)(4150 150);
WIRE 16 -1 (4150 50)(4150 150);
WIRE 16 -1 (4450 75)(4450 150);
WIRE 16 -1 (3250 -300)(3250 -325);
WIRE 16 -1 (3550 -300)(3250 -300);
WIRE 16 -1 (3250 -300)(3250 -150);
WIRE 16 -1 (3850 -300)(3550 -300);
WIRE 16 -1 (3550 -150)(3550 -300);
WIRE 16 -1 (4150 -300)(3850 -300);
WIRE 16 -1 (3850 -150)(3850 -300);
WIRE 16 -1 (4450 -300)(4150 -300);
WIRE 16 -1 (4150 -150)(4150 -300);
WIRE 16 -1 (4450 -125)(4450 -300);
WIRE 16 -1 (2400 3000)(2400 3050);
WIRE 16 -1 (2400 3000)(2750 3000);
WIRE 16 -1 (2400 3000)(2400 2925);
WIRE 16 -1 (3150 3000)(2750 3000);
WIRE 16 -1 (2750 2925)(2750 3000);
WIRE 16 -1 (3500 3000)(3150 3000);
WIRE 16 -1 (3150 2925)(3150 3000);
WIRE 16 -1 (3850 3000)(3500 3000);
WIRE 16 -1 (3500 2925)(3500 3000);
WIRE 16 -1 (4250 3000)(3850 3000);
WIRE 16 -1 (3850 2925)(3850 3000);
WIRE 16 -1 (4600 3000)(4250 3000);
WIRE 16 -1 (4250 2925)(4250 3000);
WIRE 16 -1 (5000 3000)(4600 3000);
WIRE 16 -1 (4600 2925)(4600 3000);
WIRE 16 -1 (5000 2925)(5000 3000);
WIRE 16 -1 (2400 2400)(2400 2450);
WIRE 16 -1 (2400 2450)(2750 2450);
WIRE 16 -1 (2400 2725)(2400 2450);
WIRE 16 -1 (2750 2450)(3150 2450);
WIRE 16 -1 (2750 2725)(2750 2450);
WIRE 16 -1 (3150 2450)(3500 2450);
WIRE 16 -1 (3150 2725)(3150 2450);
WIRE 16 -1 (3500 2450)(3850 2450);
WIRE 16 -1 (3500 2725)(3500 2450);
WIRE 16 -1 (4250 2450)(3850 2450);
WIRE 16 -1 (3850 2725)(3850 2450);
WIRE 16 -1 (4250 2450)(4600 2450);
WIRE 16 -1 (4250 2725)(4250 2450);
WIRE 16 -1 (4600 2450)(5000 2450);
WIRE 16 -1 (4600 2725)(4600 2450);
WIRE 16 -1 (5000 2725)(5000 2450);
WIRE 3 682 (-2400 2600)(-2400 3250);
WIRE 3 682 (-1650 2600)(-2400 2600);
WIRE 3 682 (-1650 3250)(-2400 3250);
WIRE 3 682 (-1650 3250)(-1650 2600);
WIRE 16 682 (-2475 2550)(-2475 3500);
WIRE 16 682 (-50 2550)(-2475 2550);
WIRE 16 682 (-50 3500)(-2475 3500);
WIRE 16 682 (-50 3500)(-50 2550);
WIRE 16 -1 (-1150 2300)(-1875 2300);
FORCEPROP 2 LAST SIG_NAME VSENSE_PVDDQ_GHJ_P
J 0
(-1880 2315);
DISPLAY 0.617021 (-1880 2315);
PAINT ORANGE (-1880 2315);
WIRE 16 -1 (-1150 2175)(-1150 2300);
WIRE 16 -1 (-750 2175)(-1150 2175);
WIRE 16 -1 (-750 2325)(-750 2175);
WIRE 16 -1 (-650 2175)(-650 2325);
WIRE 16 -1 (-400 2325)(-650 2325);
WIRE 16 -1 (-650 2325)(-750 2325);
WIRE 16 -1 (-650 1975)(-650 1875);
WIRE 16 -1 (-425 1875)(-650 1875);
WIRE 16 -1 (-650 1875)(-750 1875);
WIRE 16 -1 (-750 2100)(-750 1875);
WIRE 16 -1 (-1150 2100)(-750 2100);
WIRE 16 -1 (-1150 2050)(-1150 2100);
WIRE 16 -1 (-1875 2050)(-1150 2050);
FORCEPROP 2 LAST SIG_NAME VSENSE_PVDDQ_GHJ_N
J 0
(-1885 2060);
DISPLAY 0.617021 (-1885 2060);
PAINT ORANGE (-1885 2060);
WIRE 3 682 (-100 3450)(-1600 3450);
WIRE 3 682 (-100 2600)(-100 3450);
WIRE 3 682 (-1600 3450)(-1600 2600);
WIRE 3 682 (-1600 2600)(-100 2600);
WIRE 3 682 (0 2550)(0 3250);
WIRE 3 682 (0 3250)(1150 3250);
WIRE 3 682 (1150 2550)(0 2550);
WIRE 3 682 (1150 2550)(1150 3250);
WIRE 3 682 (500 1700)(1950 1700);
WIRE 3 682 (500 2450)(500 1700);
WIRE 3 682 (1950 1700)(1950 2450);
WIRE 3 682 (1950 2450)(500 2450);
WIRE 3 682 (1400 2800)(1400 3375);
WIRE 3 682 (1400 3375)(2125 3375);
WIRE 3 682 (2125 2800)(1400 2800);
WIRE 3 682 (2125 2800)(2125 3375);
WIRE 16 2175 (2175 500)(2175 3375);
WIRE 16 2175 (5375 500)(2175 500);
WIRE 16 2175 (2300 2250)(5375 2250);
WIRE 16 2175 (5375 2250)(5375 500);
WIRE 16 2175 (2175 3375)(5375 3375);
WIRE 16 2175 (5375 3375)(5375 2250);
WIRE 3 682 (-2450 650)(-2450 -850);
WIRE 3 682 (2650 650)(-2450 650);
WIRE 3 682 (-2450 -850)(2650 -850);
WIRE 3 682 (2650 -850)(2650 650);
WIRE 3 682 (2250 3200)(2250 450);
WIRE 3 682 (5350 3200)(2250 3200);
WIRE 3 682 (2250 450)(5350 450);
WIRE 3 682 (5350 450)(5350 3200);
WIRE 3 2175 (-1350 800)(1450 800);
WIRE 3 2175 (1450 1450)(1450 800);
WIRE 3 2175 (-1350 1450)(-1350 800);
WIRE 3 2175 (-1350 1450)(1450 1450);
WIRE 68 -1 (800 1400)(800 850);
WIRE 68 -1 (1400 1400)(800 1400);
WIRE 68 -1 (800 850)(1400 850);
WIRE 68 -1 (1400 850)(1400 1400);
WIRE 68 -1 (-1300 1400)(-650 1400);
WIRE 68 -1 (-650 850)(-650 1400);
WIRE 68 -1 (-1300 1400)(-1300 850);
WIRE 68 -1 (-1300 850)(-650 850);
WIRE 68 -1 (-600 1400)(-600 850);
WIRE 68 -1 (50 1400)(-600 1400);
WIRE 68 -1 (-600 850)(50 850);
WIRE 68 -1 (50 850)(50 1400);
WIRE 68 -1 (100 850)(750 850);
WIRE 68 -1 (100 1400)(100 850);
WIRE 68 -1 (750 850)(750 1400);
WIRE 68 -1 (750 1400)(100 1400);
WIRE 16 682 (3075 -625)(5250 -625);
WIRE 16 682 (3075 350)(3075 -625);
WIRE 16 682 (5250 -625)(5250 350);
WIRE 16 682 (5250 350)(3075 350);
WIRE 3 682 (2700 650)(2700 550);
WIRE 3 682 (2700 550)(2750 550);
DOT 1 (450 2650);
DOT 1 (4250 2450);
DOT 1 (2400 3000);
DOT 1 (-750 2850);
DOT 1 (4250 3000);
DOT 1 (-1100 2850);
DOT 1 (3300 1900);
DOT 1 (2900 1900);
DOT 1 (-1950 -300);
DOT 1 (-950 1350);
DOT 1 (1550 -700);
DOT 1 (3850 2450);
DOT 1 (3500 2450);
DOT 1 (-550 1350);
DOT 1 (-1125 400);
DOT 1 (-525 400);
DOT 1 (4000 1900);
DOT 1 (2750 2450);
DOT 1 (-1650 -300);
DOT 1 (1250 -300);
DOT 1 (675 400);
DOT 1 (-1950 -700);
DOT 1 (-2250 -700);
DOT 1 (1825 25);
DOT 1 (1225 25);
DOT 1 (375 25);
DOT 1 (950 25);
DOT 1 (675 25);
DOT 1 (100 -300);
DOT 1 (75 25);
DOT 1 (-525 25);
DOT 1 (-825 25);
DOT 1 (-2275 25);
DOT 1 (1525 25);
DOT 1 (-1400 25);
DOT 1 (1850 -700);
DOT 1 (-1400 400);
DOT 1 (3250 -300);
DOT 1 (700 2250);
DOT 1 (1000 2250);
DOT 1 (1300 2250);
DOT 1 (1000 1850);
DOT 1 (1300 1850);
DOT 1 (1600 1850);
DOT 1 (450 3200);
DOT 1 (-650 1875);
DOT 1 (4275 1475);
DOT 1 (3150 3000);
DOT 1 (3650 1900);
DOT 1 (3650 1475);
DOT 1 (3300 1475);
DOT 1 (3350 725);
DOT 1 (2950 1150);
DOT 1 (2600 1150);
DOT 1 (2550 1900);
DOT 1 (2950 725);
DOT 1 (1825 400);
DOT 1 (1225 400);
DOT 1 (950 400);
DOT 1 (375 400);
DOT 1 (75 400);
DOT 1 (1850 -300);
DOT 1 (1550 -300);
DOT 1 (700 -300);
DOT 1 (400 -300);
DOT 1 (-250 400);
DOT 1 (-825 400);
DOT 1 (-1675 400);
DOT 1 (-1975 400);
DOT 1 (-2275 400);
DOT 1 (-500 -300);
DOT 1 (-800 -300);
DOT 1 (-1100 -300);
DOT 1 (-1375 -300);
DOT 1 (-2250 -300);
DOT 1 (1525 400);
DOT 1 (-1650 -700);
DOT 1 (-1375 -700);
DOT 1 (-1100 -700);
DOT 1 (-800 -700);
DOT 1 (-500 -700);
DOT 1 (-225 -700);
DOT 1 (100 -700);
DOT 1 (400 -700);
DOT 1 (700 -700);
DOT 1 (975 -700);
DOT 1 (1250 -700);
DOT 1 (-250 25);
DOT 1 (-1125 25);
DOT 1 (-1675 25);
DOT 1 (-1975 25);
DOT 1 (-225 -300);
DOT 1 (975 -300);
DOT 1 (5375 2250);
DOT 1 (-650 2325);
DOT 1 (100 3200);
DOT 1 (-2325 3275);
DOT 1 (-350 2850);
DOT 1 (-1100 3275);
DOT 1 (2900 1475);
DOT 1 (450 950);
DOT 1 (850 950);
DOT 1 (450 1350);
DOT 1 (-250 1350);
DOT 1 (3850 3000);
DOT 1 (3150 2450);
DOT 1 (4600 3000);
DOT 1 (2400 2450);
DOT 1 (-2325 2700);
DOT 1 (-1450 3275);
DOT 1 (-750 3275);
DOT 1 (100 2650);
DOT 1 (2750 3000);
DOT 1 (4600 2450);
DOT 1 (3250 150);
DOT 1 (3550 -300);
DOT 1 (3550 150);
DOT 1 (3850 -300);
DOT 1 (3850 150);
DOT 1 (4150 -300);
DOT 1 (4150 150);
DOT 1 (4000 1475);
DOT 1 (-1250 950);
DOT 1 (150 1350);
DOT 1 (-1250 1350);
DOT 1 (-950 950);
DOT 1 (-550 950);
DOT 1 (-250 950);
DOT 1 (150 950);
DOT 1 (850 1350);
DOT 1 (3500 3000);
FORCENOTE
TP FAB1 CHANGE CAP 0311
(-2400 2550) 0;
DISPLAY LEFT (-2400 2550);
DISPLAY 0.638298 (-2400 2550);
PAINT RED (-2400 2550);
FORCENOTE
TP FAB3-DVT NOPOP FROM SS BOM 20161220
(-2400 2500) 0;
DISPLAY LEFT (-2400 2500);
DISPLAY 0.638298 (-2400 2500);
PAINT RED (-2400 2500);
FORCENOTE
ROOM=VDDQ_GHJ_CPU1
(-2400 2375) 0;
DISPLAY LEFT (-2400 2375);
DISPLAY 1.021277 (-2400 2375);
PAINT PURPLE (-2400 2375);
FORCENOTE
PVDDQ CPU CAVITY CAPS
(-1600 2375) 0;
DISPLAY LEFT (-1600 2375);
DISPLAY 1.021277 (-1600 2375);
PAINT PURPLE (-1600 2375);
FORCENOTE
5MIL SPACING
(-1120 1980) 0;
DISPLAY LEFT (-1120 1980);
DISPLAY 0.808511 (-1120 1980);
PAINT PURPLE (-1120 1980);
FORCENOTE
10MIL WIDTH
(-1095 2030) 0;
DISPLAY LEFT (-1095 2030);
DISPLAY 0.808511 (-1095 2030);
PAINT PURPLE (-1095 2030);
FORCENOTE
ROUT AS DIFF PAIR
(-1170 2130) 0;
DISPLAY LEFT (-1170 2130);
DISPLAY 0.808511 (-1170 2130);
PAINT PURPLE (-1170 2130);
FORCENOTE
TP FAB1 CHANGE CAP 0322
(-1600 2450) 0;
DISPLAY LEFT (-1600 2450);
DISPLAY 1.021277 (-1600 2450);
PAINT RED (-1600 2450);
FORCENOTE
TP FAB1 CHANGE CAP 0311
(350 2500) 0;
DISPLAY LEFT (350 2500);
DISPLAY 0.638298 (350 2500);
PAINT RED (350 2500);
FORCENOTE
TP FAB3-DVT NOPOP FROM SS BOM 20161220
(350 2450) 0;
DISPLAY LEFT (350 2450);
DISPLAY 0.638298 (350 2450);
PAINT RED (350 2450);
FORCENOTE
TP FAB1 CHANGE CONNECTION 0318
(1400 2725) 0;
DISPLAY LEFT (1400 2725);
DISPLAY 0.638298 (1400 2725);
PAINT RED (1400 2725);
FORCENOTE
TP FAB1 CHANGE CAPACITY 0322
(1400 2675) 0;
DISPLAY LEFT (1400 2675);
DISPLAY 0.638298 (1400 2675);
PAINT RED (1400 2675);
FORCENOTE
CAPS TO BE PLACED BETWEEN DIMMS
(2295 3255) 0;
DISPLAY LEFT (2295 3255);
DISPLAY 1.021277 (2295 3255);
PAINT PURPLE (2295 3255);
FORCENOTE
TP FAB3-DVT NOPOP FROM SS BOM 20161220
(1400 2625) 0;
DISPLAY LEFT (1400 2625);
DISPLAY 0.638298 (1400 2625);
PAINT RED (1400 2625);
FORCENOTE
TP FAB1 CHANGE ONE 47UF CPA TO TWO 22UF CAPS 0107
(-1200 1500) 0;
DISPLAY LEFT (-1200 1500);
DISPLAY 0.638298 (-1200 1500);
PAINT RED (-1200 1500);
FORCENOTE
TP FAB3-DVT NOPOP FROM SS BOM 20161220
(3900 400) 0;
DISPLAY LEFT (3900 400);
DISPLAY 0.638298 (3900 400);
PAINT RED (3900 400);
FORCENOTE
TP FAB3-DVT CHANGE CAP IN SS BOM 20161220
(2800 525) 0;
DISPLAY LEFT (2800 525);
DISPLAY 0.638298 (2800 525);
PAINT RED (2800 525);
FORCENOTE
TP FAB3-DVT CHANGE CAP C1G7, C1G12, C1G15 20161114
(-1375 750) 0;
DISPLAY LEFT (-1375 750);
DISPLAY 0.638298 (-1375 750);
PAINT RED (-1375 750);
FORCENOTE
TP FAB1 CHANGE L1F1 PN 0122
(-2450 1000) 0;
DISPLAY LEFT (-2450 1000);
DISPLAY 1.021277 (-2450 1000);
PAINT RED (-2450 1000);
FORCENOTE
PUT TOGETHER
(-1075 1400) 0;
DISPLAY LEFT (-1075 1400);
DISPLAY 0.808511 (-1075 1400);
PAINT PURPLE (-1075 1400);
FORCENOTE
INPUT FILTER
(-2005 905) 0;
DISPLAY LEFT (-2005 905);
PAINT PURPLE (-2005 905);
FORCENOTE
BOTTOM SIDE: 805
(-2279 3317) 0;
DISPLAY LEFT (-2279 3317);
DISPLAY 0.638298 (-2279 3317);
PAINT PURPLE (-2279 3317);
FORCENOTE
TOP SIDE: 603
(-1098 3317) 0;
DISPLAY LEFT (-1098 3317);
DISPLAY 0.638298 (-1098 3317);
PAINT PURPLE (-1098 3317);
FORCENOTE
TP FAB1 CHANGE CAP 0322
(-2450 -925) 0;
DISPLAY LEFT (-2450 -925);
DISPLAY 1.021277 (-2450 -925);
PAINT RED (-2450 -925);
FORCENOTE
TP FAB1 CHANGE CAP OF SINGLE SIDE 0504
(-1475 -925) 0;
DISPLAY LEFT (-1475 -925);
DISPLAY 1.021277 (-1475 -925);
PAINT RED (-1475 -925);
FORCENOTE
ROOM=VDDQ_GHJ_PWR_VR
(-2225 -1125) 0;
DISPLAY LEFT (-2225 -1125);
DISPLAY 1.595745 (-2225 -1125);
PAINT PURPLE (-2225 -1125);
FORCENOTE
CAD NOTE:
(3425 -500) 0;
DISPLAY LEFT (3425 -500);
DISPLAY 1.021277 (3425 -500);
PAINT PURPLE (3425 -500);
FORCENOTE
PLACE NEAR VR OUTPUT INDUCTORS
(3450 -575) 0;
DISPLAY LEFT (3450 -575);
DISPLAY 1.021277 (3450 -575);
PAINT PURPLE (3450 -575);
FORCENOTE
PUT TOGETHER
(100 1400) 0;
DISPLAY LEFT (100 1400);
DISPLAY 0.808511 (100 1400);
PAINT PURPLE (100 1400);
FORCENOTE
PUT TOGETHER
(-400 1400) 0;
DISPLAY LEFT (-400 1400);
DISPLAY 0.808511 (-400 1400);
PAINT PURPLE (-400 1400);
FORCENOTE
TP FAB1 CHANGE CAP 0314
(500 1625) 0;
DISPLAY LEFT (500 1625);
DISPLAY 1.021277 (500 1625);
PAINT RED (500 1625);
FORCENOTE
PUT TOGETHER
(1000 1400) 0;
DISPLAY LEFT (1000 1400);
DISPLAY 0.808511 (1000 1400);
PAINT PURPLE (1000 1400);
FORCENOTE
PVDDQ_ABC VOLTAGE SENSE
(-1845 1780) 0;
DISPLAY LEFT (-1845 1780);
PAINT PURPLE (-1845 1780);
QUIT
